G04 ================== begin FILE IDENTIFICATION RECORD ==================*
G04 Layout Name:  9054_F0T_PDB_BD_GPU_F_V04_1213_1550.brd*
G04 Film Name:    in2*
G04 File Format:  Gerber RS274X*
G04 File Origin:  Cadence Allegro 17.2-S081*
G04 Origin Date:  Wed Dec 28 10:19:02 2022*
G04 *
G04 Layer:  DRAWING FORMAT/TITLE_BLOCK_A*
G04 Layer:  PIN/SPECIAL_DRILL*
G04 Layer:  DRAWING FORMAT/TITLE_BLOCK*
G04 Layer:  VIA CLASS/IN2*
G04 Layer:  PIN/IN2*
G04 Layer:  MANUFACTURING/PHOTOPLOT_OUTLINE*
G04 Layer:  ETCH/IN2*
G04 Layer:  DRAWING FORMAT/TITLE_DATA_IN2*
G04 *
G04 Offset:    (0.00 0.00)*
G04 Mirror:    No*
G04 Mode:      Positive*
G04 Rotation:  0*
G04 FullContactRelief:  No*
G04 UndefLineWidth:     6.00*
G04 ================== end FILE IDENTIFICATION RECORD ====================*
%FSLAX25Y25*MOIN*%
%IR0*IPPOS*OFA0.00000B0.00000*MIA0B0*SFA1.00000B1.00000*%
%ADD20O,.123X.074*%
%ADD10C,.02*%
%ADD13C,.03*%
%ADD21C,.061*%
%ADD15C,.07*%
%ADD18C,.018*%
%ADD17C,.06015*%
%ADD16C,.085*%
%ADD14C,.04552*%
%ADD11C,.4*%
%ADD19C,.414*%
%ADD22C,.025*%
%ADD23C,.006*%
%ADD24C,.0051*%
%ADD27C,.03004*%
%ADD35C,.03006*%
%ADD28C,.07004*%
%ADD30C,.08004*%
%ADD37C,.07006*%
%ADD36C,.07604*%
%ADD34C,.05556*%
%ADD33C,.09556*%
%ADD29C,.12004*%
%ADD38C,.12606*%
%ADD32C,.11706*%
%ADD31O,.40438X.60123*%
%ADD26C,.16506*%
%ADD39C,.45382*%
%ADD25C,.19806*%
G75*
%LPD*%
G75*
G36*
G01X1437008Y673787D02*
X1590551D01*
G02X1608236Y656102I0J-17685D01*
G01Y642913D01*
G03X1629921Y621228I21685J0D01*
G01X1712598D01*
G02X1730283Y603543I0J-17685D01*
G01Y538465D01*
G03X1751968Y516780I21685J0D01*
G01X1854331D01*
G02X1872016Y499095I0J-17685D01*
G01Y85709D01*
G02X1854331Y68024I-17685J0D01*
G01X1751968D01*
G03X1730283Y46339I1J-21686D01*
G01Y19685D01*
G02X1712598Y2000I-17685J0D01*
G01X19685D01*
G02X2000Y19685I0J17685D01*
G01Y603543D01*
G02X19685Y621228I17685J0D01*
G01X102362D01*
G03X124047Y642913I0J21685D01*
G01Y656102D01*
G02X141732Y673787I17685J0D01*
G01X295276D01*
G02X312961Y656102I0J-17685D01*
G01Y635039D01*
G03X326772Y621228I13811J0D01*
G01X328740D01*
G02X346425Y603543I0J-17685D01*
G01Y435039D01*
G03X377952Y403512I31528J1D01*
G01X1354331D01*
G03X1385858Y435039I0J31527D01*
G01Y603543D01*
G02X1403543Y621228I17685J0D01*
G01X1405512D01*
G03X1419323Y635039I0J13811D01*
G01Y656102D01*
G02X1437008Y673787I17685J0D01*
G37*
%LPC*%
G75*
G36*
G01X1421322Y656102D02*
G02X1437008Y671788I15686J0D01*
G01X1590551D01*
G02X1606237Y656102I0J-15686D01*
G01Y642913D01*
G03X1629921Y619229I23684J0D01*
G01X1712598D01*
G02X1728284Y603543I0J-15686D01*
G01Y538465D01*
G03X1751968Y514781I23685J0D01*
G01X1854331D01*
G02X1870017Y499095I0J-15686D01*
G01Y85709D01*
G02X1854331Y70023I-15686J0D01*
G01X1751968D01*
G03X1728284Y46339I1J-23685D01*
G01Y19685D01*
G02X1712598Y3999I-15686J0D01*
G01X19685D01*
G02X3999Y19685I0J15686D01*
G01Y603543D01*
G02X19685Y619229I15686J0D01*
G01X102362D01*
G03X126046Y642913I0J23684D01*
G01Y656102D01*
G02X141732Y671788I15686J0D01*
G01X295276D01*
G02X303031Y669737I0J-15687D01*
G01X191750D01*
G02X191608Y669678I-142J141D01*
G01X154866D01*
G03X154724Y669619I0J-200D01*
G01X152891Y667786D01*
G03X152832Y667644I141J-142D01*
G01Y599674D01*
G03X152891Y599532I200J0D01*
G01X154661Y597762D01*
G03X154803Y597703I142J141D01*
G01X180582D01*
G03X180724Y597762I0J200D01*
G01X182057Y599095D01*
G03X182116Y599237I-141J142D01*
G01Y637479D01*
G02X182175Y637621I200J0D01*
G01X189925Y645371D01*
G02X190067Y645430I142J-141D01*
G01X304135D01*
G03X304277Y645489I0J200D01*
G01X305670Y646882D01*
G03X305729Y647024I-141J142D01*
G01Y667798D01*
G02X310962Y656102I-10454J-11696D01*
G01Y635039D01*
G03X326772Y619229I15810J0D01*
G01X328740D01*
G02X344426Y603543I0J-15686D01*
G01Y435039D01*
G03X377952Y401513I33527J1D01*
G01X1354331D01*
G03X1387857Y435039I0J33526D01*
G01Y603543D01*
G02X1403543Y619229I15686J0D01*
G01X1405512D01*
G03X1421322Y635039I0J15810D01*
G01Y656102D01*
G37*
G54D32*
X263780Y659961D03*
%LPD*%
G75*
G36*
G01X10467Y611952D02*
X116541D01*
G02X116683Y611893I0J-200D01*
G01X122107Y606469D01*
G02X122166Y606327I-141J-142D01*
G01Y154352D01*
G03X122225Y154210I200J0D01*
G01X161905Y114530D01*
G03X162047Y114471I142J141D01*
G01X209831D01*
G02X209960Y114424I0J-200D01*
G03X211890I965J1151D01*
G02X212019Y114471I129J-153D01*
G01X216521D01*
G02X216663Y114412I0J-200D01*
G01X231016Y100059D01*
G03X231158Y100000I142J141D01*
G01X292521D01*
G02X292663Y99941I0J-200D01*
G01X307986Y84618D01*
G03X308128Y84559I142J141D01*
G01X349986D01*
G02X350128Y84500I0J-200D01*
G01X388569Y46059D01*
G03X388711Y46000I142J141D01*
G01X394896D01*
G02X395052Y45926I1J-200D01*
G03X397380I1164J949D01*
G02X397536Y46000I155J-126D01*
G01X630321D01*
G03X630463Y46059I0J200D01*
G01X641576Y57172D01*
G03X641635Y57314I-141J142D01*
G01Y99819D01*
G02X641694Y99961I200J0D01*
G01X643439Y101706D01*
G02X643581Y101765I142J-141D01*
G01X814999D01*
G02X815193Y101615I0J-200D01*
G01X815306Y101173D01*
X815252Y101048D01*
X815192Y101015D01*
G03X807784Y88484I6894J-12531D01*
G03X822087Y74182I14302J0D01*
G03X826267Y74806I2J14302D01*
G01X826313Y74820D01*
X826406Y74804D01*
X826703Y74584D01*
G02X826784Y74423I-119J-161D01*
G01Y33732D01*
G02X826725Y33590I-200J0D01*
G01X821861Y28726D01*
G02X821719Y28667I-142J141D01*
G01X344204D01*
G02X344062Y28726I0J200D01*
G01X334260Y38528D01*
G03X334118Y38587I-142J-141D01*
G01X234733D01*
G03X234591Y38528I0J-200D01*
G01X226508Y30445D01*
G03X226449Y30303I141J-142D01*
G01Y7379D01*
G02X226390Y7237I-200J0D01*
G01X224871Y5718D01*
G02X224729Y5659I-142J141D01*
G01X16081D01*
G02X15939Y5718I0J200D01*
G01X6736Y14921D01*
G02X6677Y15063I141J142D01*
G01Y608162D01*
G02X6736Y608304I200J0D01*
G01X10325Y611893D01*
G02X10467Y611952I142J-141D01*
G37*
G36*
G01X135666Y667500D02*
X147177D01*
G02X147319Y667441I0J-200D01*
G01X148145Y666615D01*
G02X148204Y666473I-141J-142D01*
G01Y595359D01*
G03X148263Y595217I200J0D01*
G01X150383Y593097D01*
G03X150525Y593038I142J141D01*
G01X185999D01*
G03X186141Y593097I0J200D01*
G01X187912Y594868D01*
G03X187971Y595010I-141J142D01*
G01Y633887D01*
G02X188030Y634029I200J0D01*
G01X190442Y636441D01*
G02X190584Y636500I142J-141D01*
G01X202619D01*
G02X202795Y636394I-1J-200D01*
G03X212953I5079J2700D01*
G02X213129Y636500I177J-94D01*
G01X304109D01*
G02X304251Y636441I0J-200D01*
G01X306435Y634257D01*
G02X306494Y634115I-141J-142D01*
G01Y610141D01*
G02X306435Y609999I-200J0D01*
G01X288194Y591758D01*
G03X288135Y591616I141J-142D01*
G01Y547631D01*
G03X288194Y547489I200J0D01*
G01X300867Y534816D01*
G03X301009Y534757I142J141D01*
G01X329401D01*
G02X329543Y534698I0J-200D01*
G01X334941Y529300D01*
G02X335000Y529158I-141J-142D01*
G01Y417577D01*
G03X335059Y417435I200J0D01*
G01X359382Y393112D01*
G03X359524Y393053I142J141D01*
G01X433514D01*
X441852Y384715D01*
Y340424D01*
X423600Y322172D01*
Y295615D01*
X425458Y293757D01*
G03X425600Y293698I142J141D01*
G01X467441D01*
G02X467583Y293639I0J-200D01*
G01X468279Y292943D01*
G02X468338Y292801I-141J-142D01*
G01Y275568D01*
G02X468279Y275426I-200J0D01*
G01X467314Y274461D01*
G02X467172Y274402I-142J141D01*
G01X426893D01*
G03X426751Y274343I0J-200D01*
G01X423600Y271192D01*
Y251154D01*
X425397Y249357D01*
G03X425539Y249298I142J141D01*
G01X467441D01*
G02X467583Y249239I0J-200D01*
G01X468279Y248543D01*
G02X468338Y248401I-141J-142D01*
G01Y231168D01*
G02X468279Y231026I-200J0D01*
G01X467314Y230061D01*
G02X467172Y230002I-142J141D01*
G01X426333D01*
G03X426191Y229943I0J-200D01*
G01X423600Y227352D01*
Y206061D01*
X424704Y204957D01*
G03X424846Y204898I142J141D01*
G01X467441D01*
G02X467583Y204839I0J-200D01*
G01X468279Y204143D01*
G02X468338Y204001I-141J-142D01*
G01Y186768D01*
G02X468279Y186626I-200J0D01*
G01X467314Y185661D01*
G02X467172Y185602I-142J141D01*
G01X428173D01*
G03X428031Y185543I0J-200D01*
G01X423600Y181112D01*
Y163700D01*
X426743Y160557D01*
X467465D01*
X468338Y159684D01*
Y142285D01*
X467255Y141202D01*
X427102D01*
X425400Y139500D01*
Y117800D01*
X427102Y116098D01*
X467524D01*
X468338Y115284D01*
Y97884D01*
X467256Y96802D01*
X427402D01*
X425400Y94800D01*
Y73000D01*
X426800Y71600D01*
X467622D01*
X468338Y70884D01*
Y53485D01*
X467255Y52402D01*
X399479D01*
X392201Y59680D01*
G02X392059Y59739I0J200D01*
G01X356331Y95467D01*
G03X356189Y95526I-142J-141D01*
G01X322520D01*
G02X322378Y95585I0J200D01*
G01X304730Y113233D01*
G03X304588Y113292I-142J-141D01*
G01X231068D01*
G02X230926Y113351I0J200D01*
G01X217135Y127142D01*
X165442D01*
X134083Y158500D01*
G02X134024Y158642I141J142D01*
G01Y587858D01*
G02X134083Y588000I200J0D01*
G01Y665917D01*
G02X134142Y666059I200J0D01*
G01X135524Y667441D01*
G02X135666Y667500I142J-141D01*
G37*
G36*
G01X460766Y400453D02*
X1149707D01*
G02X1149741Y400450I-1J-200D01*
G02X1149847Y400396I-34J-197D01*
G01X1153887Y396356D01*
G02X1153899Y396343I-141J-142D01*
G01X1153946Y396296D01*
Y380804D01*
G02X1153887Y380662I-200J0D01*
G01X1150785Y377559D01*
X1144372Y371146D01*
X1144344Y371117D01*
X1144270Y371087D01*
X1056496D01*
G02X1056354Y371146I0J200D01*
G01X1050118Y377382D01*
G03X1049976Y377441I-142J-141D01*
G01X1043226D01*
G02X1043122Y377470I0J200D01*
G01X1043121Y377471D01*
G03X1043018Y377500I-104J-171D01*
G01X1011223D01*
G03X1011081Y377441I0J-200D01*
G01X1009432Y375792D01*
G03X1009373Y375650I141J-142D01*
G01Y302083D01*
G02X1009314Y301941I-200J0D01*
G01X1006035Y298662D01*
X1006007Y298633D01*
X1005933Y298603D01*
X948418D01*
G02X948221Y299351I0J400D01*
G03X956449Y313484I-8024J14133D01*
G03X923945I-16252J0D01*
G03X932173Y299351I16252J0D01*
G02X931976Y298603I-197J-348D01*
G01X908815D01*
G03X908673Y298544I0J-200D01*
G01X893621Y283492D01*
G03X893562Y283350I141J-142D01*
G01Y114121D01*
G03X893621Y113979I200J0D01*
G01X905207Y102393D01*
G03X905349Y102334I142J141D01*
G01X930380D01*
G02X930615Y101611I-1J-400D01*
G03X923945Y88484I9582J-13127D01*
G03X956449I16252J0D01*
G03X949779Y101611I-16252J0D01*
G02X950014Y102334I236J323D01*
G01X973010D01*
G02X973190Y102220I-1J-200D01*
G01X973209Y102180D01*
X973214Y102164D01*
X973305Y101859D01*
G02X973289Y101707I-192J-57D01*
G01Y101706D01*
X973242Y101623D01*
X973209Y101587D01*
X973189Y101573D01*
G03X964034Y84650I11064J-16923D01*
G01Y64962D01*
G03X1004472I20219J0D01*
G01Y84647D01*
G03X995283Y101593I-20220J0D01*
G01X995282Y101594D01*
X995273Y101600D01*
X995260Y101610D01*
G02X995190Y101826I122J159D01*
G01X995299Y102191D01*
G02X995490Y102334I192J-57D01*
G01X1089683D01*
G02X1089717Y102331I-1J-200D01*
G02X1089823Y102277I-34J-197D01*
G01X1091725Y100375D01*
G02X1091784Y100233I-141J-142D01*
G01Y61707D01*
G03X1091843Y61565I200J0D01*
G01X1108349Y45059D01*
G03X1108491Y45000I142J141D01*
G01X1320817D01*
G03X1320959Y45059I0J200D01*
G01X1335779Y59879D01*
G02X1335921Y59938I142J-141D01*
G01X1397504D01*
G03X1397646Y59997I0J200D01*
G01X1406124Y68475D01*
X1406171Y68501D01*
X1406198Y68508D01*
G03X1406293Y68561I-46J194D01*
G01X1456364Y118632D01*
G02X1456506Y118691I142J-141D01*
G01X1588517D01*
G03X1588659Y118750I0J200D01*
G01X1594099Y124190D01*
Y124189D01*
X1595197Y125287D01*
G02X1595362Y125344I141J-142D01*
G01X1595646Y125310D01*
X1595687Y125295D01*
X1595705Y125284D01*
X1595781Y125238D01*
X1595798Y125221D01*
X1595846Y125174D01*
X1595870Y125140D01*
G03X1597100Y124498I1230J857D01*
G03X1598602Y126000I0J1502D01*
G01Y126002D01*
G03X1598601Y126025I-1500J-54D01*
G01X1598600Y126032D01*
Y126080D01*
G02X1598625Y126176I200J-1D01*
G01X1598636Y126197D01*
G02X1598666Y126238I175J-97D01*
G01X1598853Y126437D01*
G02X1598998Y126500I146J-137D01*
G01X1615517D01*
G02X1615551Y126497I-1J-200D01*
G02X1615657Y126443I-34J-197D01*
G01X1620982Y121118D01*
G03X1621124Y121059I142J141D01*
G01X1622558D01*
G02X1622592Y121056I-1J-200D01*
G02X1622698Y121002I-34J-197D01*
G01X1623841Y119859D01*
G02X1623900Y119717I-141J-142D01*
G01Y113243D01*
X1623870Y113169D01*
X1623841Y113141D01*
X1621159Y110459D01*
G03X1621100Y110317I141J-142D01*
G01Y102783D01*
G03X1621159Y102641I200J0D01*
G01X1626641Y97159D01*
G03X1626783Y97100I142J141D01*
G01X1648655D01*
G02X1648784Y97053I0J-200D01*
G03X1653290I2253J2681D01*
G02X1653419Y97100I129J-153D01*
G01X1665017D01*
G03X1665159Y97159I0J200D01*
G01X1680291Y112291D01*
G03X1680350Y112433I-141J142D01*
G01Y140105D01*
G03X1680291Y140247I-200J0D01*
G01X1678559Y141979D01*
X1678530Y142007D01*
X1678500Y142081D01*
Y173834D01*
G02X1678559Y173976I200J0D01*
G01X1680291Y175708D01*
G03X1680350Y175850I-141J142D01*
G01Y179667D01*
G02X1680409Y179809I200J0D01*
G01X1685596Y184996D01*
X1685687Y185025D01*
G03X1685975Y184997I289J1475D01*
G03X1686215Y185016I2J1503D01*
G01X1686243Y185012D01*
G02X1686307Y184990I-32J-198D01*
G01X1686337Y184973D01*
X1686578Y184714D01*
G02X1686632Y184578I-146J-137D01*
G01Y184541D01*
X1686628Y184521D01*
G03X1686597Y184222I1472J-304D01*
G01Y184220D01*
G03X1688100Y185723I1503J0D01*
G03X1687889Y185709I-6J-1503D01*
G01X1687840Y185702D01*
X1687750Y185734D01*
X1687494Y186007D01*
G02X1687440Y186166I145J138D01*
G03X1687478Y186500I-1465J336D01*
G03X1687450Y186788I-1503J-1D01*
G01X1687479Y186879D01*
X1722541Y221941D01*
G03X1722600Y222083I-141J142D01*
G01Y300917D01*
G02X1722659Y301059I200J0D01*
G01X1726441Y304841D01*
G02X1726583Y304900I142J-141D01*
G01X1811917D01*
G02X1811951Y304897I-1J-200D01*
G02X1812057Y304843I-34J-197D01*
G01X1818714Y298186D01*
G02X1818773Y298044I-141J-142D01*
G01Y189637D01*
X1818722Y189546D01*
X1818676Y189519D01*
X1818389Y189346D01*
G02X1818236Y189323I-104J171D01*
G01X1818211Y189329D01*
X1818174Y189343D01*
X1818163Y189347D01*
X1818151Y189352D01*
X1818146Y189354D01*
G03X1817500Y189502I-650J-1353D01*
G03Y186498I0J-1502D01*
G03X1818167Y186655I-1J1502D01*
G01X1818169Y186656D01*
X1818190Y186666D01*
X1818238Y186678D01*
X1818240D01*
X1818268Y186686D01*
X1818334Y186681D01*
X1818366Y186668D01*
X1818383Y186662D01*
X1818678Y186481D01*
G02X1818773Y186311I-105J-170D01*
G01Y123759D01*
G02X1818611Y123563I-200J0D01*
G01X1818247Y123492D01*
G02X1818067Y123547I-38J196D01*
G01X1818003Y123611D01*
X1817987Y123649D01*
X1817986Y123651D01*
X1817983Y123659D01*
G03X1778994Y116143I-18770J-7516D01*
G01Y96458D01*
G03X1818002Y88990I20219J0D01*
G01Y88991D01*
G02X1818226Y89112I185J-75D01*
G01X1818611Y89038D01*
G02X1818773Y88842I-38J-196D01*
G01Y76348D01*
X1818743Y76274D01*
X1818714Y76246D01*
X1813551Y71083D01*
G02X1813409Y71024I-142J141D01*
G01X1751968D01*
G03X1727282Y46339I0J-24686D01*
G01Y19683D01*
G02X1712598Y5000I-14684J1D01*
G01X1701576D01*
G02X1701398Y5110I1J200D01*
G01X1701277Y5350D01*
G02X1701256Y5440I179J89D01*
G01Y5601D01*
X1701265Y5630D01*
X1701276Y5666D01*
X1701297Y5694D01*
G03X1705260Y17716I-16254J12022D01*
G01Y37402D01*
G03X1664822I-20219J0D01*
G01Y17715D01*
G03X1668825Y5639I20219J1D01*
G01X1668859Y5594D01*
X1668869Y5482D01*
X1668683Y5111D01*
G02X1668670Y5088I-180J87D01*
G02X1668515Y5000I-166J112D01*
G02X1668504I-5J200D01*
G01X1496685D01*
X1496611Y5030D01*
X1496583Y5059D01*
X1496555Y5087D01*
X1496399Y5434D01*
Y5562D01*
G02X1496450Y5695I200J0D01*
G03X1486409Y5668I-5033J4502D01*
G01X1486449Y5624D01*
X1486467Y5508D01*
X1486294Y5119D01*
X1486270Y5064D01*
X1486171Y5000D01*
X1479669D01*
G02X1479496Y5100I0J200D01*
G01X1479322Y5401D01*
G02X1479323Y5602I173J100D01*
G03X1479975Y8011I-4126J2409D01*
G01Y8012D01*
G03X1475197Y12790I-4778J0D01*
G03X1473536Y12491I3J-4777D01*
G01X1473520Y12485D01*
X1473439Y12467D01*
X1473355Y12485D01*
X1473320Y12511D01*
X1473104Y12669D01*
G02X1473022Y12836I118J162D01*
G01Y12845D01*
G03X1473027Y13010I-2825J168D01*
G01Y13012D01*
G03X1470197Y10182I-2830J0D01*
G01X1470199D01*
G03X1470366Y10187I-1J2830D01*
G01X1470377D01*
G02X1470539Y10105I1J-200D01*
G01X1470700Y9884D01*
G02X1470739Y9766I-161J-119D01*
G01X1470726Y9696D01*
G03X1470419Y8012I4470J-1685D01*
G01Y8011D01*
G03X1471071Y5602I4778J0D01*
G02X1471072Y5401I-172J-101D01*
G01X1470898Y5100D01*
G02X1470725Y5000I-173J100D01*
G01X1467009D01*
G02X1466844Y5086I-1J200D01*
G01X1466823Y5117D01*
X1466812Y5156D01*
X1466713Y5473D01*
Y5475D01*
X1466705Y5490D01*
Y5589D01*
X1466767Y5706D01*
X1466784Y5725D01*
X1466799Y5742D01*
X1466818Y5756D01*
X1466819Y5757D01*
G03X1467975Y8012I-1621J2255D01*
G03X1462419I-2778J0D01*
G03X1463575Y5757I2777J0D01*
G01X1463576Y5756D01*
X1463595Y5742D01*
X1463610Y5725D01*
X1463627Y5706D01*
X1463639Y5683D01*
G03X1463653Y5660I178J92D01*
G01X1463676Y5628D01*
X1463687Y5585D01*
G02X1463683Y5477I-195J-47D01*
G01X1463557Y5077D01*
X1463450Y4999D01*
X1463384Y5000D01*
G03X1463381I-1J-200D01*
G01X306134D01*
X306060Y5030D01*
X306032Y5059D01*
X306004Y5087D01*
X305848Y5434D01*
Y5562D01*
G02X305899Y5695I200J0D01*
G03X295857Y5669I-5033J4502D01*
G01X295897Y5625D01*
X295916Y5508D01*
X295743Y5119D01*
X295719Y5064D01*
X295620Y5000D01*
X289064D01*
X288972Y5053D01*
X288945Y5100D01*
X288772Y5399D01*
Y5401D01*
X288759Y5414D01*
X288741Y5547D01*
X288798Y5648D01*
G03X289424Y8011I-4152J2364D01*
G01Y8012D01*
G03X284646Y12790I-4778J0D01*
G03X282984Y12490I4J-4777D01*
G01X282965Y12483D01*
X282921Y12476D01*
X282920D01*
G02X282769Y12511I-34J197D01*
G01X282592Y12641D01*
G02X282510Y12813I118J162D01*
G01Y12817D01*
G03X282517Y13009I-2864J201D01*
G01Y13012D01*
G03X279646Y10141I-2871J0D01*
G01X279651D01*
G03X279841Y10148I-11J2871D01*
G01X279894Y10152D01*
X279986Y10109D01*
X280149Y9885D01*
G02X280175Y9697I-161J-118D01*
G01Y9696D01*
G03X279868Y8012I4470J-1685D01*
G01Y8011D01*
G03X280519Y5603I4778J0D01*
G01X280547Y5556D01*
Y5450D01*
X280350Y5104D01*
G02X280254Y5018I-174J98D01*
G01X280248Y5016D01*
X280210Y5000D01*
X276470D01*
G02X276446Y5001I-4J200D01*
G01X276433Y5003D01*
G02X276292Y5088I24J199D01*
G01X276272Y5117D01*
X276261Y5156D01*
X276162Y5473D01*
Y5475D01*
X276150Y5508D01*
X276156Y5592D01*
X276216Y5706D01*
X276233Y5725D01*
X276248Y5742D01*
X276267Y5756D01*
X276268Y5757D01*
G03X277424Y8012I-1621J2255D01*
G03X271868I-2778J0D01*
G03X273024Y5757I2777J0D01*
G01X273025Y5756D01*
X273044Y5742D01*
X273059Y5725D01*
X273076Y5706D01*
X273134Y5595D01*
X273138Y5558D01*
X273143Y5515D01*
X273130Y5474D01*
X273006Y5077D01*
X272900Y4999D01*
X272833Y5000D01*
G03X272830I-1J-200D01*
G01X231300D01*
G02X231100Y5200I0J200D01*
G01Y29017D01*
G02X231159Y29159I200J0D01*
G01X237041Y35041D01*
G02X237183Y35100I142J-141D01*
G01X332738D01*
G02X332772Y35097I-1J-200D01*
G02X332878Y35043I-34J-197D01*
G01X343362Y24559D01*
G03X343504Y24500I142J141D01*
G01X835517D01*
G03X835659Y24559I0J200D01*
G01X838730Y27630D01*
G03X838789Y27772I-141J142D01*
G01Y363316D01*
G03X838730Y363458I-200J0D01*
G01X830093Y372095D01*
X830063Y372167D01*
Y372207D01*
G03X825900Y376363I-4163J-7D01*
G01X825899D01*
G03X823124Y375303I1J-4164D01*
G01X823111Y375291D01*
X823066Y375263D01*
G02X823034Y375247I-105J170D01*
G01X822985Y375228D01*
G02X822912Y375214I-74J186D01*
G01X765130D01*
G02X765036Y375238I1J200D01*
G01X764957Y375280D01*
G02X764884Y375345I93J177D01*
G01Y375346D01*
G03X731195Y375367I-16851J-11173D01*
G01X731181Y375346D01*
X731128Y375298D01*
X731109Y375281D01*
X731029Y375238D01*
G02X730934Y375214I-95J176D01*
G01X719583D01*
G03X719441Y375155I0J-200D01*
G01X717059Y372773D01*
G03X717000Y372631I141J-142D01*
G01Y336583D01*
G03X717059Y336441I200J0D01*
G01X736441Y317059D01*
G02X736500Y316917I-141J-142D01*
G01Y306583D01*
G02X736441Y306441I-200J0D01*
G01X728059Y298059D01*
X728031Y298030D01*
X727957Y298000D01*
X725083D01*
G02X724941Y298059I0J200D01*
G01X724559Y298441D01*
X724530Y298469D01*
X724500Y298543D01*
Y300417D01*
G03X724441Y300559I-200J0D01*
G01X723559Y301441D01*
G03X723417Y301500I-142J-141D01*
G01X686666D01*
G03X686524Y301441I0J-200D01*
G01X685130Y300047D01*
G02X685085Y300013I-142J141D01*
G01X685063Y300001D01*
X685036Y299994D01*
X685035D01*
G03X684941Y299941I48J-194D01*
G01X678159Y293159D01*
G03X678100Y293017I141J-142D01*
G01Y283766D01*
X678070Y283692D01*
X678041Y283664D01*
X676887Y282510D01*
X676859Y282481D01*
X676785Y282451D01*
X676695D01*
X676686Y282452D01*
X676683D01*
G03X675758Y282131I3J-1502D01*
G01X675756Y282130D01*
X675744Y282121D01*
X675722Y282108D01*
G02X675624Y282082I-99J174D01*
G01X674745D01*
G02X674643Y282110I0J200D01*
G01X674624Y282121D01*
X674612Y282130D01*
X674610Y282131D01*
G03X673684Y282452I-928J-1181D01*
G03X672758Y282131I2J-1502D01*
G01X672756Y282130D01*
X672744Y282121D01*
X672722Y282108D01*
G02X672624Y282082I-99J174D01*
G01X661638D01*
X661564Y282112D01*
X661536Y282141D01*
X660400Y283277D01*
X660376Y283393D01*
X660398Y283449D01*
G03X660503Y284000I-1398J552D01*
G03X659000Y285503I-1503J0D01*
G03X658449Y285398I1J-1503D01*
G01X658393Y285376D01*
X658277Y285400D01*
X656559Y287118D01*
X656530Y287146D01*
X656500Y287220D01*
Y325120D01*
G02X657026Y325499I400J-1D01*
G03X657500Y325422I475J1426D01*
G03Y328428I0J1503D01*
G03X657026Y328351I1J-1503D01*
G02X656500Y328730I-126J380D01*
G01Y352317D01*
G03X656441Y352459I-200J0D01*
G01X650059Y358841D01*
G03X649917Y358900I-142J-141D01*
G01X459100D01*
X456798Y361202D01*
Y396485D01*
G02X456857Y396627I200J0D01*
G01X460624Y400394D01*
G02X460766Y400453I142J-141D01*
G37*
G36*
G01X500010Y340800D02*
X527517D01*
G02X527659Y340741I0J-200D01*
G01X537968Y330432D01*
G03X538110Y330373I142J141D01*
G01X616876D01*
G02X616964Y330353I1J-200D01*
G03X618500Y329998I1536J3147D01*
G03X620036Y330353I0J3502D01*
G02X620124Y330373I87J-180D01*
G01X631380D01*
G02X631522Y330314I0J-200D01*
G01X637041Y324795D01*
G02X637100Y324653I-141J-142D01*
G01Y300271D01*
G03X637159Y300129I200J0D01*
G01X647426Y289862D01*
G02X647485Y289720I-141J-142D01*
G01Y264598D01*
G03X647544Y264456I200J0D01*
G01X651941Y260059D01*
G03X652083Y260000I142J141D01*
G01X652266D01*
X652316Y259986D01*
X652339Y259973D01*
G03X654100Y259498I1761J3027D01*
G03X655594Y259833I-1J3502D01*
G02X655765I86J-181D01*
G03X657259Y259498I1495J3167D01*
G03X658432Y259700I1J3502D01*
G02X658617Y259673I67J-188D01*
G03X660684Y258998I2067J2827D01*
G03X663080Y259946I0J3502D01*
G02X663217Y260000I137J-146D01*
G01X679973D01*
X680089Y259887D01*
X680091Y259806D01*
G03X683592Y256406I3501J103D01*
G03X685924Y257296I-1J3502D01*
G01X685953Y257321D01*
X686024Y257347D01*
X686376Y257338D01*
X686446Y257308D01*
X686473Y257281D01*
G03X688945Y256259I2472J2479D01*
G03X691619Y257500I0J3501D01*
G02X691773Y257571I153J-129D01*
G01X691794D01*
G03X695082Y259869I0J3501D01*
G02X695270Y260000I188J-69D01*
G01X703518D01*
G02X703705Y259870I0J-200D01*
G03X706984Y257598I3279J1230D01*
G03X708450Y257920I-1J3502D01*
G02X708618I84J-182D01*
G03X710084Y257598I1467J3180D01*
G03X713586Y261100I0J3502D01*
G03X711234Y264408I-3502J0D01*
G02X711100Y264597I66J189D01*
G01Y274417D01*
G02X711159Y274559I200J0D01*
G01X712541Y275941D01*
G02X712683Y276000I142J-141D01*
G01X720517D01*
G02X720659Y275941I0J-200D01*
G01X721541Y275059D01*
G02X721600Y274917I-141J-142D01*
G01Y256083D01*
G02X721541Y255941I-200J0D01*
G01X718659Y253059D01*
G02X718517Y253000I-142J141D01*
G01X653389D01*
G02X653211Y253108I0J200D01*
G03X652714Y253831I-3112J-1607D01*
G02X652665Y253993I149J133D01*
G03X652702Y254500I-3465J508D01*
G03X645698I-3502J0D01*
G03X645840Y253513I3501J0D01*
G01X645854Y253467D01*
X645837Y253375D01*
X645616Y253080D01*
G02X645456Y253000I-160J120D01*
G01X633683D01*
G02X633541Y253059I0J200D01*
G01X628659Y257941D01*
G02X628600Y258083I141J142D01*
G01Y271500D01*
G02X628632Y271608I200J0D01*
G03X629186Y273499I-2948J1890D01*
G03X629179Y273719I-3502J-1D01*
G02X629225Y273860I200J13D01*
G01X629302Y273952D01*
G02X629432Y274023I154J-128D01*
G03X632520Y277500I-414J3477D01*
G03X631009Y280381I-3502J0D01*
G01X630960Y280415D01*
X630915Y280523D01*
X631003Y280999D01*
X631083Y281084D01*
X631141Y281099D01*
G03X633810Y284500I-832J3401D01*
G03X630308Y288002I-3502J0D01*
G03X629134Y287799I1J-3502D01*
G01X629087Y287783D01*
X628992Y287796D01*
X628685Y288013D01*
G02X628600Y288176I115J164D01*
G01Y319106D01*
G03X628541Y319248I-200J0D01*
G01X625683Y322106D01*
G03X625541Y322165I-142J-141D01*
G01X534518D01*
G02X534376Y322224I0J200D01*
G01X524259Y332341D01*
G03X524117Y332400I-142J-141D01*
G01X518251D01*
X518228Y332406D01*
G03X517410Y332502I-814J-3406D01*
G03X516592Y332406I-4J-3502D01*
G01X516569Y332400D01*
X507150D01*
X507127Y332406D01*
G03X506309Y332502I-814J-3406D01*
G03X505491Y332406I-4J-3502D01*
G01X505468Y332400D01*
X503018D01*
G03X502876Y332341I0J-200D01*
G01X492759Y322224D01*
G02X492617Y322165I-142J141D01*
G01X486041D01*
G03X485899Y322106I0J-200D01*
G01X481798Y318005D01*
G03X481739Y317863I141J-142D01*
G01Y171148D01*
G02X481680Y171006I-200J0D01*
G01X478283Y167609D01*
G02X478141Y167550I-142J141D01*
G01X431106D01*
G02X430964Y167609I0J200D01*
G01X430743Y167830D01*
G02X430684Y167972I141J142D01*
G01Y173526D01*
G02X430743Y173668I200J0D01*
G01X433044Y175969D01*
G02X433186Y176028I142J-141D01*
G01X439907D01*
X440011Y175952D01*
X440032Y175889D01*
G03X443844I1906J610D01*
G01X443865Y175952D01*
X443969Y176028D01*
X466020D01*
G03X466162Y176087I0J200D01*
G01X472124Y182049D01*
G03X472183Y182191I-141J142D01*
G01Y206345D01*
G03X472124Y206487I-200J0D01*
G01X469698Y208913D01*
G03X469556Y208972I-142J-141D01*
G01X436778D01*
G02X436636Y209031I0J200D01*
G01X434707Y210960D01*
G02X434648Y211102I141J142D01*
G01Y217326D01*
G02X434707Y217468I200J0D01*
G01X436947Y219708D01*
G02X437089Y219767I142J-141D01*
G01X440185D01*
G02X440345Y219688I1J-200D01*
G03X443531I1593J1211D01*
G02X443691Y219767I159J-121D01*
G01X467944D01*
G03X468086Y219826I0J200D01*
G01X472124Y223864D01*
G03X472183Y224006I-141J142D01*
G01Y327808D01*
G02X472242Y327950I200J0D01*
G01X474606Y330314D01*
G02X474748Y330373I142J-141D01*
G01X489417D01*
G03X489559Y330432I0J200D01*
G01X499868Y340741D01*
G02X500010Y340800I142J-141D01*
G37*
G36*
G01X702984Y268898D02*
G03X704734Y269367I-1J3502D01*
G01X704757Y269380D01*
X704807Y269394D01*
X704861D01*
X704911Y269380D01*
X704934Y269367D01*
G03X706684Y268898I1751J3033D01*
G03X707595Y269019I-2J3502D01*
G01X707641Y269031D01*
X707732Y269013D01*
X708022Y268791D01*
G02X708100Y268633I-122J-158D01*
G01Y266083D01*
G02X708041Y265941I-200J0D01*
G01X706740Y264640D01*
G02X706622Y264583I-141J142D01*
G01X706620D01*
G03X704100Y263087I364J-3483D01*
G02X703935Y263000I-165J113D01*
G01X662176D01*
X662077Y263064D01*
X662053Y263118D01*
G03X659315I-1369J-618D01*
G01X659291Y263064D01*
X659192Y263000D01*
X659108D01*
G02X658966Y263059I0J200D01*
G01X658773Y263252D01*
G02X658721Y263345I142J140D01*
G01X658720Y263347D01*
Y263348D01*
G03X657607Y264461I-1461J-348D01*
G01X657606D01*
X657604Y264462D01*
G02X657511Y264514I47J194D01*
G01X650045Y271980D01*
G02X650032Y271994I140J143D01*
G02X649986Y272122I154J128D01*
G01Y290756D01*
Y290757D01*
G03X649928Y290898I-200J0D01*
G01X649869Y290957D01*
G02X649810Y291098I141J142D01*
G01Y292189D01*
G03X649751Y292331I-200J0D01*
G01X641159Y300923D01*
X641130Y300951D01*
X641100Y301025D01*
Y317917D01*
G03X641070Y318022I-200J0D01*
G01X641056Y318046D01*
X641041Y318098D01*
Y326296D01*
G03X640982Y326438I-200J0D01*
G01X633638Y333782D01*
G03X633496Y333841I-142J-141D01*
G01X620114D01*
G02X619997Y333879I0J200D01*
G01X619996D01*
G02X619924Y333976I117J162D01*
G01Y333978D01*
G03X617076I-1424J-478D01*
G01Y333976D01*
G02X617004Y333879I-189J65D01*
G01X617003D01*
G02X616886Y333841I-117J162D01*
G01X538179D01*
G02X538038Y333900I1J200D01*
G01X528695Y343243D01*
G03X528553Y343302I-142J-141D01*
G01X498974D01*
G03X498832Y343243I0J-200D01*
G01X489489Y333900D01*
G02X489347Y333841I-142J141D01*
G01X456676D01*
G02X456534Y333900I0J200D01*
G01X454435Y335999D01*
X454406Y336027D01*
X454376Y336101D01*
Y352317D01*
G02X454433Y352457I200J0D01*
G01X454434Y352458D01*
X457017Y355041D01*
G02X457019Y355043I142J-140D01*
G02X457159Y355100I140J-143D01*
G01X642917D01*
G02X643057Y355043I0J-200D01*
G01X643058Y355042D01*
X651441Y346659D01*
G02X651443Y346657I-140J-142D01*
G02X651500Y346517I-143J-140D01*
G01Y296083D01*
G03X651559Y295941I200J0D01*
G01X652941Y294559D01*
G02X652943Y294557I-140J-142D01*
G02X653000Y294417I-143J-140D01*
G01Y281183D01*
G03X653059Y281041I200J0D01*
G01X658041Y276059D01*
G03X658183Y276000I142J141D01*
G01X679017D01*
G03X679122Y276030I0J200D01*
G01X679146Y276044D01*
X679198Y276059D01*
X679476D01*
G03X679618Y276118I0J200D01*
G01X694441Y290941D01*
G02X694443Y290943I142J-140D01*
G02X694583Y291000I140J-143D01*
G01X721711D01*
G02X721889Y290892I0J-200D01*
G03X728111I3111J1608D01*
G02X728289Y291000I178J-92D01*
G01X734917D01*
G03X735059Y291059I0J200D01*
G01X741441Y297441D01*
G03X741500Y297583I-141J142D01*
G01Y323417D01*
G03X741441Y323559I-200J0D01*
G01X729059Y335941D01*
X729030Y335969D01*
X729000Y336043D01*
Y370417D01*
G02X729057Y370557I200J0D01*
G01X729058Y370558D01*
X732231Y373731D01*
G02X732233Y373733I142J-140D01*
G02X732373Y373790I140J-143D01*
G01X819487D01*
G02X819520Y373787I-2J-200D01*
G02X819627Y373733I-32J-197D01*
G01X822242Y371118D01*
X822266Y371078D01*
X822273Y371055D01*
G03X824755Y368573I3627J1145D01*
G01X824778Y368566D01*
X824818Y368542D01*
X826707Y366653D01*
G02X826746Y366424I-141J-142D01*
G01X826581Y366083D01*
G02X826376Y365972I-180J87D01*
G03X825900Y366002I-477J-3772D01*
G03Y358398I0J-3802D01*
G03X828129Y359120I0J3802D01*
G01X828130D01*
G02X828337Y359136I117J-162D01*
G01X828655Y358974D01*
G02X828764Y358796I-91J-178D01*
G01Y326779D01*
G02X828671Y326610I-200J0D01*
G01X828391Y326433D01*
G02X828240Y326406I-108J168D01*
G01X828196Y326416D01*
X828177Y326425D01*
G03X822089Y327786I-6089J-12941D01*
G01X822087D01*
G03Y299182I0J-14302D01*
G01X822089D01*
G03X828177Y300543I-1J14302D01*
G01X828196Y300552D01*
X828240Y300562D01*
G02X828391Y300535I43J-195D01*
G01X828671Y300358D01*
G02X828764Y300189I-107J-169D01*
G01Y214335D01*
G02X828705Y214193I-200J0D01*
G01X825766Y211254D01*
X825738Y211225D01*
X825664Y211195D01*
X721252D01*
G03X721110Y211136I0J-200D01*
G01X709099Y199125D01*
G03X709040Y198983I141J-142D01*
G01Y195001D01*
G02X708981Y194859I-200J0D01*
G01X708109Y193987D01*
X708081Y193958D01*
X708007Y193928D01*
X702377D01*
G02X702235Y193987I0J200D01*
G01X701253Y194969D01*
X701224Y194997D01*
X701194Y195071D01*
Y195624D01*
G02X701279Y195787I200J-1D01*
G01X701586Y196005D01*
X701681Y196018D01*
X701727Y196002D01*
G03X702223Y195917I498J1417D01*
G03Y198921I0J1502D01*
G03X701727Y198836I2J-1502D01*
G01X701681Y198820D01*
X701586Y198833D01*
X701279Y199051D01*
G02X701194Y199214I115J164D01*
G01Y227138D01*
G03X701135Y227280I-200J0D01*
G01X695172Y233243D01*
G03X695030Y233302I-142J-141D01*
G01X674969D01*
G03X674827Y233243I0J-200D01*
G01X665128Y223544D01*
X665100Y223515D01*
X665026Y223485D01*
X629483D01*
X629409Y223515D01*
X629381Y223544D01*
X600021Y252903D01*
X599992Y252931D01*
X599962Y253005D01*
Y294083D01*
G02X599967Y294128I200J1D01*
G01X599978Y294172D01*
G02X599993Y294215I195J-44D01*
G01X600004Y294237D01*
X600295Y294458D01*
G02X600379Y294495I121J-160D01*
G01X600424Y294503D01*
X600470Y294491D01*
X600472D01*
G03X600875Y294435I406J1446D01*
G03X600994Y294440I-3J1502D01*
G01X600997D01*
G02X601149Y294385I14J-199D01*
G01X601397Y294148D01*
X601429Y294070D01*
X601427Y294026D01*
G03X601426Y293969I1501J-55D01*
G03X602928Y292467I1502J0D01*
G03X603971Y292888I0J1502D01*
G01X604010Y292926D01*
X604111Y292951D01*
X604495Y292846D01*
G02X604635Y292705I-53J-193D01*
G03X606084Y291598I1449J395D01*
G03Y294602I0J1502D01*
G03X605041Y294181I0J-1502D01*
G01X605002Y294143D01*
X604901Y294118D01*
X604517Y294223D01*
G02X604377Y294364I53J193D01*
G03X602928Y295471I-1449J-395D01*
G03X602809Y295466I3J-1502D01*
G01X602806D01*
G02X602654Y295521I-14J199D01*
G01X602406Y295758D01*
X602374Y295836D01*
X602376Y295880D01*
G03X602377Y295937I-1501J55D01*
G03X600875Y297439I-1502J0D01*
G03X600472Y297383I3J-1502D01*
G01X600470D01*
X600424Y297371D01*
X600379Y297379D01*
G02X600295Y297416I37J197D01*
G01X600041Y297609D01*
G02X599962Y297768I121J159D01*
G01Y313455D01*
G03X599903Y313597I-200J0D01*
G01X596559Y316941D01*
G03X596417Y317000I-142J-141D01*
G01X592147D01*
G02X592068Y317016I-1J200D01*
G03X590684Y317302I-1386J-3216D01*
G03X589300Y317016I2J-3502D01*
G02X589221Y317000I-78J184D01*
G01X589083D01*
G03X588941Y316941I0J-200D01*
G01X588653Y316653D01*
X588640Y316643D01*
G03X587843Y315847I2044J-2843D01*
G01X587841Y315844D01*
X587831Y315831D01*
X587750Y315750D01*
Y315713D01*
X587719Y315664D01*
G03X587182Y313801I2965J-1864D01*
G01Y313800D01*
G03X587482Y312381I3502J-1D01*
G02Y312219I-183J-81D01*
G03X587182Y310800I3202J-1418D01*
G03X587483Y309380I3502J0D01*
G02X587500Y309299I-183J-81D01*
G01Y299583D01*
G03X587559Y299441I200J0D01*
G01X594441Y292559D01*
G02X594443Y292557I-140J-142D01*
G02X594500Y292417I-143J-140D01*
G01Y269583D01*
G02X594441Y269441I-200J0D01*
G01X590776Y265776D01*
X590748Y265747D01*
X590674Y265717D01*
X580155D01*
G02X579956Y265899I0J200D01*
G01Y265900D01*
G03X572978I-3489J-300D01*
G01Y265899D01*
G02X572779Y265717I-199J18D01*
G01X566713D01*
G02X566565Y265783I0J200D01*
G01X566366Y266002D01*
G02X566315Y266156I148J134D01*
G03X566332Y266500I-3485J345D01*
G03X565916Y268155I-3502J0D01*
G01X565904Y268178D01*
X565892Y268225D01*
Y268275D01*
X565904Y268322D01*
X565916Y268345D01*
G03X566332Y270000I-3086J1655D01*
G03X565916Y271655I-3502J0D01*
G01X565904Y271678D01*
X565892Y271725D01*
Y271775D01*
X565904Y271822D01*
X565916Y271845D01*
G03X566332Y273500I-3086J1655D01*
G03X565916Y275155I-3502J0D01*
G01X565904Y275178D01*
X565892Y275225D01*
Y275275D01*
X565904Y275322D01*
X565916Y275345D01*
G03X566332Y277000I-3086J1655D01*
G03X559328I-3502J0D01*
G03X559744Y275345I3502J0D01*
G01X559756Y275322D01*
X559768Y275275D01*
Y275225D01*
X559756Y275178D01*
X559744Y275155D01*
G03X559328Y273500I3086J-1655D01*
G03X559744Y271845I3502J0D01*
G01X559756Y271822D01*
X559768Y271775D01*
Y271725D01*
X559756Y271678D01*
X559744Y271655D01*
G03X559328Y270000I3086J-1655D01*
G03X559744Y268345I3502J0D01*
G01X559756Y268322D01*
X559768Y268275D01*
Y268225D01*
X559756Y268178D01*
X559744Y268155D01*
G03X559328Y266500I3086J-1655D01*
G03X559345Y266156I3502J1D01*
G02X559294Y266002I-199J-20D01*
G01X559095Y265783D01*
G02X558947Y265717I-148J134D01*
G01X555118D01*
G02X554919Y265899I0J200D01*
G01Y265900D01*
G03X547941I-3489J-300D01*
G01Y265899D01*
G02X547742Y265717I-199J18D01*
G01X543112D01*
G02X542970Y265776I0J200D01*
G01X539444Y269302D01*
G02X539386Y269443I142J141D01*
G01Y314453D01*
G03X539327Y314595I-200J0D01*
G01X539322Y314600D01*
G02X539263Y314742I141J142D01*
G01Y317135D01*
G02X539320Y317275I200J0D01*
G01X539321Y317276D01*
X541650Y319605D01*
G02X541664Y319618I143J-140D01*
G02X541792Y319664I128J-154D01*
G01X623485D01*
G02X623613Y319618I0J-200D01*
G01X623620Y319612D01*
X625828Y317404D01*
G02X625830Y317402I-140J-142D01*
G02X625887Y317262I-143J-140D01*
G01Y275284D01*
G02X625828Y275142I-200J0D01*
G01X625743Y275057D01*
G02X625729Y275045I-137J145D01*
G02X625632Y275001I-128J154D01*
G02X625611Y274999I-29J198D01*
G03Y271999I73J-1500D01*
G02X625632Y271997I-8J-200D01*
G02X625729Y271953I-31J-198D01*
G02X625743Y271941I-123J-157D01*
G01X625828Y271856D01*
G02X625832Y271851I-154J-127D01*
G01X625833D01*
G02X625887Y271714I-146J-137D01*
G01Y256492D01*
G03X625946Y256350I200J0D01*
G01X632770Y249526D01*
G03X632912Y249467I142J141D01*
G01X632952D01*
X633025Y249497D01*
X633028Y249500D01*
X690543D01*
G02X690720Y249393I0J-200D01*
G01X690885Y249080D01*
G02X690907Y248974I-177J-92D01*
G01X690904Y248919D01*
X690873Y248873D01*
X690872Y248872D01*
G03X690607Y248020I1236J-852D01*
G03X692109Y246518I1502J0D01*
G03X693353Y247178I0J1502D01*
G02X693519Y247266I166J-112D01*
G01X693849D01*
G02X694015Y247178I0J-200D01*
G03X695259Y246518I1244J842D01*
G03X696308Y246945I0J1502D01*
G02X696502Y246994I139J-143D01*
G01X696837Y246900D01*
G02X696925Y246847I-56J-192D01*
G01X696944Y246827D01*
X696970Y246782D01*
X696976Y246755D01*
G03X698433Y245617I1457J364D01*
G03Y248621I0J1502D01*
G03X697384Y248194I0J-1502D01*
G02X697190Y248145I-139J143D01*
G01X696855Y248239D01*
G02X696767Y248292I56J192D01*
G01X696748Y248312D01*
X696722Y248357D01*
X696716Y248384D01*
G03X696496Y248872I-1457J-363D01*
G01X696495Y248873D01*
X696494Y248874D01*
G02X696461Y248973I167J111D01*
G01Y248974D01*
G02X696483Y249080I199J14D01*
G01X696648Y249393D01*
G02X696825Y249500I177J-93D01*
G01X720017D01*
G03X720159Y249559I0J200D01*
G01X725041Y254441D01*
G03X725100Y254583I-141J142D01*
G01Y266712D01*
G02X725128Y266814I200J0D01*
G02X725204Y266887I172J-103D01*
G01X725511Y267055D01*
G02X725715Y267048I96J-175D01*
G03X727599Y266498I1884J2952D01*
G01X727601D01*
G03X729019Y266798I0J3502D01*
G02X729181I81J-183D01*
G03X730598Y266498I1418J3202D01*
G01X730600D01*
G03Y273502I0J3502D01*
G01X730598D01*
G03X729181Y273202I1J-3502D01*
G02X729019I-81J183D01*
G03X727601Y273502I-1418J-3202D01*
G01X727599D01*
G03X725715Y272952I0J-3502D01*
G02X725511Y272945I-108J168D01*
G01X725204Y273113D01*
G02X725100Y273288I96J175D01*
G01Y276917D01*
G03X725041Y277059I-200J0D01*
G01X723012Y279088D01*
X722982Y279155D01*
X722980Y279192D01*
G03X719484Y282482I-3496J-212D01*
G03X716178Y280134I0J-3501D01*
G02X716175Y280126I-189J66D01*
G02X715994Y280000I-186J74D01*
G01X711183D01*
G03X711041Y279941I0J-200D01*
G01X708159Y277059D01*
G03X708100Y276917I141J-142D01*
G01Y276167D01*
G02X708022Y276009I-200J0D01*
G01X707732Y275787D01*
X707641Y275769D01*
X707595Y275781D01*
G03X706684Y275902I-913J-3381D01*
G03X704934Y275433I1J-3502D01*
G01X704911Y275420D01*
X704861Y275406D01*
X704807D01*
X704757Y275420D01*
X704734Y275433D01*
G03X702984Y275902I-1751J-3033D01*
G03Y268898I0J-3502D01*
G37*
G36*
G01X519884Y181700D02*
X487384D01*
X486284Y180600D01*
Y52100D01*
X487584Y50800D01*
X519784D01*
X559784D01*
X560449Y51465D01*
Y113228D01*
Y113735D01*
X558984Y115200D01*
Y117300D01*
Y117400D01*
Y117500D01*
X560484Y119000D01*
Y129700D01*
X560284Y129900D01*
X541684D01*
X541000Y130584D01*
Y153500D01*
X546500Y159000D01*
X553800D01*
X561000Y166200D01*
Y178000D01*
X558500Y180500D01*
X558342Y180342D01*
X536842D01*
X535484Y181700D01*
X529784D01*
X519884D01*
G37*
G36*
G01Y314900D02*
X487384D01*
X486284Y313800D01*
Y185300D01*
X487584Y184000D01*
X519784D01*
X559784D01*
X560449Y184665D01*
Y246428D01*
Y246935D01*
X558984Y248400D01*
Y250500D01*
Y250600D01*
Y250700D01*
X560484Y252200D01*
Y262900D01*
X560284Y263100D01*
X541684D01*
X536884Y267900D01*
Y313500D01*
X535484Y314900D01*
X529784D01*
X519884D01*
G37*
G36*
G01X565685Y262968D02*
X584461D01*
X585964Y261464D01*
Y235536D01*
X600500Y221000D01*
X626429D01*
X630929Y216500D01*
X690300D01*
X692003Y214797D01*
Y211285D01*
X684133Y203415D01*
X678547D01*
X675872Y200740D01*
Y170609D01*
X683819Y162662D01*
X755950D01*
X779288Y186000D01*
X825201D01*
G02X825343Y185941I0J-200D01*
G01X826725Y184559D01*
G02X826784Y184417I-141J-142D01*
G01Y119746D01*
X826754Y119716D01*
Y119337D01*
G02X826695Y119195I-200J0D01*
G01X822545Y115045D01*
X637425D01*
X630919Y108539D01*
Y60576D01*
X620761Y50418D01*
X566529D01*
X565554Y51393D01*
Y113755D01*
X567116Y115317D01*
Y117384D01*
X565555Y118945D01*
Y129638D01*
X565685Y129768D01*
X582000D01*
X584000Y131768D01*
Y153000D01*
X577500Y159500D01*
X571700D01*
X565554Y165646D01*
Y246955D01*
X567116Y248517D01*
Y250584D01*
X565555Y252145D01*
Y262838D01*
X565685Y262968D01*
G37*
G36*
G01X720246Y200520D02*
X758811D01*
X760285Y199046D01*
Y183828D01*
X746957Y170500D01*
X732780D01*
X719273Y184007D01*
Y199547D01*
X720246Y200520D01*
G37*
G36*
G01X1175654Y262968D02*
X1194552D01*
X1195168Y262352D01*
Y173585D01*
X1183083Y161500D01*
G03X1182941Y161441I0J-200D01*
G01X1175775Y154275D01*
G03X1175716Y154133I141J-142D01*
G01Y131155D01*
X1177103Y129768D01*
X1194842D01*
X1195168Y129442D01*
Y51178D01*
X1194408Y50418D01*
X1113993D01*
X1100334Y64077D01*
Y105768D01*
X1091057Y115045D01*
X907614D01*
G02X907472Y115104I0J200D01*
G01X905559Y117017D01*
G02X905500Y117159I141J142D01*
G01Y184417D01*
G02X905559Y184559I200J0D01*
G01X906941Y185941D01*
G02X907083Y186000I142J-141D01*
G01X956100D01*
X979438Y162662D01*
X1009300D01*
X1020238Y173600D01*
X1056428D01*
X1093528Y210700D01*
X1166484D01*
X1169784Y214000D01*
Y257098D01*
X1175654Y262968D01*
G37*
G36*
G01X1186783Y387700D02*
X1342717D01*
G02X1342857Y387643I0J-200D01*
G01X1342858Y387642D01*
X1351096Y379404D01*
G02X1351098Y379402I-140J-142D01*
G02X1351155Y379262I-143J-140D01*
G01Y330082D01*
G02X1351096Y329940I-200J0D01*
G01X1346336Y325180D01*
X1346308Y325151D01*
X1346234Y325121D01*
X1333496D01*
G02X1333354Y325180I0J200D01*
G01X1318793Y339741D01*
G03X1318651Y339800I-142J-141D01*
G01X1164303D01*
G02X1164151Y339870I0J200D01*
G01X1163953Y340102D01*
G02X1163908Y340263I152J129D01*
G03X1163927Y340500I-1483J238D01*
G03X1160923I-1502J0D01*
G03X1160942Y340263I1502J1D01*
G02X1160897Y340102I-197J-32D01*
G01X1160699Y339870D01*
G02X1160547Y339800I-152J130D01*
G01X1116583D01*
G02X1116441Y339859I0J200D01*
G01X1115459Y340841D01*
X1115430Y340869D01*
X1115400Y340943D01*
Y342017D01*
G02X1115457Y342157I200J0D01*
G01X1115458Y342158D01*
X1116441Y343141D01*
G03X1116500Y343283I-141J142D01*
G01Y348217D01*
G03X1116441Y348359I-200J0D01*
G01X1115959Y348841D01*
G03X1115817Y348900I-142J-141D01*
G01X1097883D01*
G02X1097741Y348959I0J200D01*
G01X1097159Y349541D01*
G03X1097017Y349600I-142J-141D01*
G01X1037183D01*
G03X1037041Y349541I0J-200D01*
G01X1023859Y336359D01*
G03X1023800Y336217I141J-142D01*
G01Y217741D01*
G02X1023741Y217599I-200J0D01*
G01X1018133Y211991D01*
X1018105Y211962D01*
X1018031Y211932D01*
X907033D01*
G02X906891Y211991I0J200D01*
G01X904717Y214165D01*
X904688Y214193D01*
X904658Y214267D01*
Y279973D01*
G02X904715Y280113I200J0D01*
G01X904716Y280114D01*
X915683Y291081D01*
G02X915685Y291083I142J-140D01*
G02X915825Y291140I140J-143D01*
G01X1009220D01*
G03X1009362Y291199I0J200D01*
G01X1013604Y295441D01*
G03X1013663Y295583I-141J142D01*
G01Y372041D01*
G02X1013720Y372181I200J0D01*
G01X1013721Y372182D01*
X1014863Y373324D01*
G02X1014865Y373326I142J-140D01*
G02X1015005Y373383I140J-143D01*
G01X1048434D01*
G02X1048574Y373326I0J-200D01*
G01X1048575Y373325D01*
X1061041Y360859D01*
G03X1061183Y360800I142J141D01*
G01X1092600D01*
G02X1092738Y360745I0J-200D01*
G01X1092966Y360528D01*
X1092998Y360459D01*
X1093000Y360420D01*
G03X1096000I1500J80D01*
G01X1096002Y360459D01*
X1096034Y360528D01*
X1096262Y360745D01*
G02X1096400Y360800I138J-145D01*
G01X1165698D01*
G02X1165898Y360600I0J-200D01*
G01Y355000D01*
G03X1165974Y354469I1902J1D01*
G01X1165986Y354429D01*
X1165975Y354347D01*
X1165784Y354024D01*
X1165717Y353976D01*
X1165676Y353967D01*
G03X1164815Y353423I324J-1467D01*
G02X1164657Y353346I-158J123D01*
G01X1164343D01*
G02X1164185Y353423I0J200D01*
G03X1163000Y354002I-1185J-923D01*
G03Y350998I0J-1502D01*
G03X1164185Y351577I0J1502D01*
G02X1164343Y351654I158J-123D01*
G01X1164657D01*
G02X1164815Y351577I0J-200D01*
G03X1166000Y350998I1185J923D01*
G03X1167502Y352500I0J1502D01*
G01Y352501D01*
G03X1167494Y352658I-1502J2D01*
G01X1167489Y352700D01*
X1167514Y352779D01*
X1167759Y353063D01*
X1167834Y353098D01*
X1167876Y353100D01*
G03X1169702Y355000I-75J1900D01*
G01Y360600D01*
G02X1169902Y360800I200J0D01*
G01X1171117D01*
G03X1171259Y360859I0J200D01*
G01X1176841Y366441D01*
G03X1176900Y366583I-141J142D01*
G01Y377817D01*
G02X1176957Y377957I200J0D01*
G01X1176958Y377958D01*
X1186641Y387641D01*
G02X1186643Y387643I142J-140D01*
G02X1186783Y387700I140J-143D01*
G37*
G36*
G01X974461Y200520D02*
X1013026D01*
X1014500Y199046D01*
Y183828D01*
X1001172Y170500D01*
X986995D01*
X973488Y184007D01*
Y199547D01*
X974461Y200520D01*
G37*
G36*
G01X1057883Y335800D02*
X1227309D01*
G02X1227451Y335741I0J-200D01*
G01X1238193Y324999D01*
G03X1238335Y324940I142J141D01*
G01X1280889D01*
G02X1281031Y324881I0J-200D01*
G01X1289281Y316631D01*
G02X1289340Y316489I-141J-142D01*
G01Y205507D01*
G03X1289399Y205365I200J0D01*
G01X1295624Y199140D01*
G03X1295766Y199081I142J141D01*
G01X1323925D01*
G02X1324067Y199022I0J-200D01*
G01X1327397Y195692D01*
G02X1327456Y195550I-141J-142D01*
G01Y190974D01*
G02X1327397Y190832I-200J0D01*
G01X1325298Y188733D01*
G02X1325156Y188674I-142J141D01*
G01X1291269D01*
G03X1291127Y188615I0J-200D01*
G01X1289399Y186887D01*
G03X1289340Y186745I141J-142D01*
G01Y161910D01*
G03X1289399Y161768I200J0D01*
G01X1296486Y154681D01*
G03X1296628Y154622I142J141D01*
G01X1325772D01*
G02X1325914Y154563I0J-200D01*
G01X1326473Y154004D01*
G02X1326532Y153862I-141J-142D01*
G01Y146391D01*
G02X1326473Y146249I-200J0D01*
G01X1326283Y146059D01*
G02X1326141Y146000I-142J141D01*
G01X1283572D01*
G02X1283430Y146059I0J200D01*
G01X1281393Y148096D01*
G02X1281334Y148238I141J142D01*
G01Y313964D01*
G03X1281275Y314106I-200J0D01*
G01X1277020Y318361D01*
G03X1276878Y318420I-142J-141D01*
G01X1228386D01*
G02X1228244Y318479I0J200D01*
G01X1216182Y330541D01*
G03X1216040Y330600I-142J-141D01*
G01X1062483D01*
G03X1062341Y330541I0J-200D01*
G01X1049159Y317359D01*
G03X1049100Y317217I141J-142D01*
G01Y292578D01*
G02X1049078Y292487I-200J0D01*
G03X1048698Y290900I3122J-1587D01*
G03X1049078Y289313I3502J0D01*
G02X1049100Y289222I-178J-91D01*
G01Y278483D01*
G02X1049041Y278341I-200J0D01*
G01X1047359Y276659D01*
G02X1047217Y276600I-142J141D01*
G01X1042583D01*
G02X1042441Y276659I0J200D01*
G01X1041459Y277641D01*
G02X1041400Y277783I141J142D01*
G01Y319317D01*
G02X1041459Y319459I200J0D01*
G01X1057741Y335741D01*
G02X1057883Y335800I142J-141D01*
G37*
G36*
G01X1059300Y283102D02*
G03X1057551Y282633I2J-3502D01*
G01X1057550D01*
X1057548Y282632D01*
G02X1057352I-98J174D01*
G01X1057350Y282633D01*
X1057349D01*
G03X1055600Y283102I-1751J-3033D01*
G03X1052886Y281813I0J-3502D01*
G01X1052880Y281806D01*
G02X1052656Y281742I-157J124D01*
G01X1052302Y281869D01*
X1052242Y281890D01*
X1052169Y281993D01*
Y287202D01*
G02X1052360Y287402I200J0D01*
G03X1053665Y287720I-161J3498D01*
G01X1053666D01*
X1053668Y287721D01*
G02X1053834Y287720I82J-182D01*
G03X1055300Y287398I1467J3180D01*
G03Y294402I0J3502D01*
G03X1053834Y294080I1J-3502D01*
G01X1053794Y294061D01*
X1053708D01*
X1053666Y294080D01*
X1053665D01*
G03X1052360Y294398I-1466J-3180D01*
G02X1052340Y294400I10J200D01*
G02X1052169Y294598I29J198D01*
G01Y312890D01*
G02X1052228Y313032I200J0D01*
G01X1059789Y320593D01*
G02X1059931Y320652I142J-141D01*
G01X1063576D01*
X1063604Y320644D01*
G03X1064600Y320498I1001J3356D01*
G03X1065596Y320644I-5J3502D01*
G01X1065624Y320652D01*
X1071576D01*
X1071604Y320644D01*
G03X1072600Y320498I1001J3356D01*
G03X1073596Y320644I-5J3502D01*
G01X1073624Y320652D01*
X1079576D01*
X1079604Y320644D01*
G03X1080600Y320498I1001J3356D01*
G03X1081596Y320644I-5J3502D01*
G01X1081624Y320652D01*
X1083869D01*
G03X1084011Y320711I0J200D01*
G01X1088441Y325141D01*
G02X1088583Y325200I142J-141D01*
G01X1119948D01*
G02X1120126Y325090I-1J-200D01*
G01X1120285Y324778D01*
G02X1120305Y324672I-179J-89D01*
G01Y324671D01*
G02X1120269Y324571I-199J15D01*
G01X1120268Y324570D01*
X1120267Y324569D01*
G03X1119592Y322500I2833J-2069D01*
G03X1119889Y321089I3508J2D01*
G01X1119894Y321077D01*
X1119901Y321054D01*
X1119908Y321030D01*
X1119911Y320980D01*
X1119898Y320920D01*
X1119890Y320900D01*
X1119889Y320897D01*
X1119886Y320889D01*
G03X1119598Y319502I3214J-1391D01*
G01Y319500D01*
G03X1126602I3502J0D01*
G01Y319502D01*
G03X1126312Y320894I-3502J-3D01*
G01X1126311Y320897D01*
X1126303Y320917D01*
X1126294Y320960D01*
G02X1126292Y321022I196J37D01*
G01X1126295Y321053D01*
X1126307Y321081D01*
G03X1126608Y322500I-3207J1422D01*
G03X1125950Y324544I-3508J-1D01*
G01X1125932Y324570D01*
X1125910Y324638D01*
Y324640D01*
X1125897Y324678D01*
X1125903Y324757D01*
X1126074Y325091D01*
G02X1126149Y325171I178J-92D01*
G01X1126150D01*
G02X1126252Y325200I104J-171D01*
G01X1209637D01*
G02X1209670Y325197I-2J-200D01*
G02X1209777Y325143I-32J-197D01*
G01X1221929Y312991D01*
G02X1221988Y312849I-141J-142D01*
G01Y269388D01*
X1221958Y269314D01*
X1221929Y269286D01*
X1218304Y265661D01*
G02X1218162Y265602I-142J141D01*
G01X1214116D01*
X1214001Y265711D01*
X1213997Y265791D01*
G03X1207003I-3497J-191D01*
G01X1206999Y265711D01*
X1206884Y265602D01*
X1202970D01*
G02X1202820Y265670I0J200D01*
G01X1202622Y265896D01*
G02X1202573Y266039I150J131D01*
G01X1202574Y266058D01*
Y266065D01*
G03X1202602Y266500I-3474J442D01*
G03X1202187Y268154I-3502J0D01*
G01X1202186Y268155D01*
X1202185Y268157D01*
G02Y268343I177J93D01*
G01X1202186Y268345D01*
X1202187Y268346D01*
G03X1202602Y270000I-3087J1654D01*
G03X1202187Y271654I-3502J0D01*
G01X1202186Y271655D01*
X1202185Y271657D01*
G02Y271843I177J93D01*
G01X1202186Y271845D01*
X1202187Y271846D01*
G03X1202602Y273500I-3087J1654D01*
G03X1202187Y275154I-3502J0D01*
G01X1202186Y275155D01*
X1202185Y275157D01*
G02Y275343I177J93D01*
G01X1202186Y275345D01*
X1202187Y275346D01*
G03X1202602Y277000I-3087J1654D01*
G03X1195598I-3502J0D01*
G03X1196013Y275346I3502J0D01*
G01X1196014Y275345D01*
X1196015Y275343D01*
G02Y275157I-177J-93D01*
G01X1196014Y275155D01*
X1196013Y275154D01*
G03X1195598Y273500I3087J-1654D01*
G03X1196013Y271846I3502J0D01*
G01X1196014Y271845D01*
X1196015Y271843D01*
G02Y271657I-177J-93D01*
G01X1196014Y271655D01*
X1196013Y271654D01*
G03X1195598Y270000I3087J-1654D01*
G03X1196013Y268346I3502J0D01*
G01X1196014Y268345D01*
X1196015Y268343D01*
G02Y268157I-177J-93D01*
G01X1196014Y268155D01*
X1196013Y268154D01*
G03X1195598Y266500I3087J-1654D01*
G01Y266499D01*
G03X1195644Y265934I3502J1D01*
G01X1195649Y265902D01*
X1195644Y265868D01*
G02X1195598Y265770I-197J33D01*
G01X1195401Y265540D01*
G02X1195249Y265470I-152J130D01*
G01X1191401D01*
G02X1191201Y265665I0J200D01*
G01Y265667D01*
G03X1184199Y265666I-3501J-66D01*
G01X1184197Y265584D01*
X1184081Y265470D01*
X1174701D01*
G03X1174559Y265411I0J-200D01*
G01X1167341Y258193D01*
G03X1167282Y258051I141J-142D01*
G01Y246696D01*
X1167252Y246622D01*
X1167223Y246594D01*
X1153888Y233259D01*
G02X1153746Y233200I-142J141D01*
G01X1110883D01*
G03X1110741Y233141I0J-200D01*
G01X1082009Y204409D01*
G02X1081867Y204350I-142J141D01*
G01X1049493D01*
X1049419Y204380D01*
X1049391Y204409D01*
X1043459Y210341D01*
G02X1043400Y210483I141J142D01*
G01Y269217D01*
G02X1043459Y269359I200J0D01*
G01X1043713Y269613D01*
G02X1043796Y269663I142J-141D01*
G01X1043797D01*
G03X1045477Y270761I-996J3358D01*
G01X1045504Y270793D01*
X1045613Y270847D01*
G02X1045701Y270867I87J-180D01*
G01X1048955D01*
G03X1049097Y270926I0J200D01*
G01X1052110Y273939D01*
G03X1052169Y274081I-141J142D01*
G01Y277143D01*
G02X1052302Y277331I200J0D01*
G01X1052718Y277479D01*
X1052839Y277445D01*
X1052879Y277395D01*
G03X1055600Y276098I2721J2206D01*
G03X1057349Y276567I-2J3502D01*
G01X1057350D01*
X1057352Y276568D01*
G02X1057548I98J-174D01*
G01X1057550Y276567D01*
X1057551D01*
G03X1059300Y276098I1751J3033D01*
G03Y283102I0J3502D01*
G37*
G36*
G01X1226800Y181700D02*
X1274900D01*
X1276000Y180600D01*
Y52100D01*
X1274700Y50800D01*
X1203809D01*
X1203300Y51309D01*
Y129580D01*
X1203620Y129900D01*
X1220600D01*
X1225400Y134700D01*
Y180300D01*
X1226800Y181700D01*
G37*
G36*
G01Y314900D02*
X1274900D01*
X1276000Y313800D01*
Y185300D01*
X1274700Y184000D01*
X1203832D01*
X1203300Y184532D01*
Y262522D01*
X1203878Y263100D01*
X1220600D01*
X1225400Y267900D01*
Y313500D01*
X1226800Y314900D01*
G37*
G36*
G01X1564583Y667500D02*
X1577957D01*
X1578031Y667470D01*
X1578059Y667441D01*
X1579441Y666059D01*
G02X1579500Y665917I-141J-142D01*
G01Y588083D01*
G03X1579559Y587941I200J0D01*
G01X1583441Y584059D01*
G03X1583583Y584000I142J141D01*
G01X1629457D01*
X1629531Y583970D01*
X1629559Y583941D01*
X1633882Y579618D01*
G02X1633941Y579476I-141J-142D01*
G01Y538641D01*
G03X1633970Y538538I200J1D01*
G01X1633971Y538537D01*
X1633985Y538513D01*
X1633992Y538488D01*
G02X1634000Y538433I-192J-56D01*
G01Y213043D01*
X1633970Y212969D01*
X1633941Y212941D01*
X1601612Y180612D01*
G03X1601553Y180470I141J-142D01*
G01Y170139D01*
G02X1601494Y169997I-200J0D01*
G01X1594559Y163062D01*
G03X1594500Y162920I141J-142D01*
G01Y154957D01*
G02X1594441Y154815I-200J0D01*
G01X1594161Y154535D01*
G02X1594019Y154476I-142J141D01*
G01X1589548D01*
G03X1589406Y154417I0J-200D01*
G01X1587050Y152061D01*
G03X1586991Y151919I141J-142D01*
G01Y128728D01*
G02X1586932Y128586I-200J0D01*
G01X1586358Y128012D01*
G02X1586216Y127953I-142J141D01*
G01X1545144D01*
G02X1545002Y128012I0J200D01*
G01X1543897Y129117D01*
G03X1543755Y129176I-142J-141D01*
G01X1446818D01*
G03X1446676Y129117I0J-200D01*
G01X1395059Y77500D01*
X1294025D01*
X1293600Y77925D01*
Y95998D01*
X1293800Y96198D01*
X1333298D01*
X1336589Y99489D01*
Y118011D01*
X1333198Y121402D01*
X1294060D01*
X1293600Y121862D01*
Y140398D01*
X1293800Y140598D01*
X1333198D01*
X1337100Y144500D01*
Y164315D01*
X1335672Y165743D01*
G03X1335530Y165802I-142J-141D01*
G01X1294142D01*
G02X1294000Y165861I0J200D01*
G01X1293659Y166202D01*
G02X1293600Y166344I141J142D01*
G01Y184715D01*
G02X1293659Y184857I200J0D01*
G01X1293741Y184939D01*
G02X1293883Y184998I142J-141D01*
G01X1335828D01*
G03X1335970Y185057I0J200D01*
G01X1337100Y186187D01*
Y208158D01*
X1335115Y210143D01*
G03X1334973Y210202I-142J-141D01*
G01X1294142D01*
G02X1294000Y210261I0J200D01*
G01X1293659Y210602D01*
G02X1293600Y210744I141J142D01*
G01Y229115D01*
G02X1293659Y229257I200J0D01*
G01X1293741Y229339D01*
G02X1293883Y229398I142J-141D01*
G01X1335585D01*
G03X1335727Y229457I0J200D01*
G01X1337100Y230830D01*
Y251878D01*
X1334435Y254543D01*
G03X1334293Y254602I-142J-141D01*
G01X1294142D01*
G02X1294000Y254661I0J200D01*
G01X1293659Y255002D01*
G02X1293600Y255144I141J142D01*
G01Y273515D01*
G02X1293659Y273657I200J0D01*
G01X1293741Y273739D01*
G02X1293883Y273798I142J-141D01*
G01X1335279D01*
G03X1335421Y273857I0J200D01*
G01X1337100Y275536D01*
Y296767D01*
X1334926Y298941D01*
G03X1334784Y299000I-142J-141D01*
G01X1294145D01*
G02X1294003Y299059I0J200D01*
G01X1293659Y299403D01*
G02X1293600Y299545I141J142D01*
G01Y313417D01*
G02X1293659Y313559I200J0D01*
G01X1294541Y314441D01*
G02X1294683Y314500I142J-141D01*
G01X1359863D01*
G03X1360005Y314559I0J200D01*
G01X1363416Y317970D01*
G02X1363474Y318010I141J-142D01*
G01Y318028D01*
X1370900Y325454D01*
Y396300D01*
X1399041Y424441D01*
G03X1399100Y424583I-141J142D01*
G01Y531990D01*
G02X1399159Y532132I200J0D01*
G01X1401088Y534061D01*
G02X1401230Y534120I142J-141D01*
G01X1429126D01*
G03X1429268Y534179I0J200D01*
G01X1443437Y548348D01*
G03X1443496Y548490I-141J142D01*
G01Y593086D01*
G03X1443437Y593228I-200J0D01*
G01X1427414Y609251D01*
G02X1427355Y609393I141J142D01*
G01Y635766D01*
G02X1427414Y635908I200J0D01*
G01X1427947Y636441D01*
G02X1428089Y636500I142J-141D01*
G01X1519154D01*
G02X1519330Y636394I-1J-200D01*
G03X1529488I5079J2700D01*
G02X1529664Y636500I177J-94D01*
G01X1560417D01*
G03X1560559Y636559I0J200D01*
G01X1561941Y637941D01*
G03X1562000Y638083I-141J142D01*
G01Y664957D01*
X1562030Y665031D01*
X1562059Y665059D01*
X1564441Y667441D01*
G02X1564583Y667500I142J-141D01*
G37*
G36*
G01X1429981Y668790D02*
X1542860D01*
G02X1543002Y668731I0J-200D01*
G01X1544458Y667275D01*
G02X1544517Y667133I-141J-142D01*
G01Y646707D01*
G02X1544458Y646565I-200J0D01*
G01X1542749Y644856D01*
G02X1542607Y644797I-142J141D01*
G01X1525166D01*
X1525153Y644799D01*
G03X1523665I-744J-5705D01*
G01X1523652Y644797D01*
X1428543D01*
G02X1428401Y644856I0J200D01*
G01X1426504Y646753D01*
G02X1426445Y646895I141J142D01*
G01Y665254D01*
G02X1426504Y665396I200J0D01*
G01X1429839Y668731D01*
G02X1429981Y668790I142J-141D01*
G37*
G36*
G01X1586413Y667506D02*
X1598275D01*
G02X1598417Y667447I0J-200D01*
G01X1599811Y666053D01*
G02X1599870Y665911I-141J-142D01*
G01Y621683D01*
G03X1599929Y621541I200J0D01*
G01X1604410Y617060D01*
G03X1604552Y617001I142J141D01*
G01X1715403D01*
G02X1715545Y616942I0J-200D01*
G01X1725503Y606984D01*
G02X1725562Y606842I-141J-142D01*
G01Y526278D01*
G03X1725621Y526136I200J0D01*
G01X1742381Y509376D01*
G03X1742523Y509317I142J141D01*
G01X1859232D01*
G02X1859374Y509258I0J-200D01*
G01X1866057Y502575D01*
G02X1866116Y502433I-141J-142D01*
G01Y80631D01*
G02X1866057Y80489I-200J0D01*
G01X1857361Y71793D01*
G02X1857219Y71734I-142J141D01*
G01X1825396D01*
G02X1825254Y71793I0J200D01*
G01X1823231Y73816D01*
G02X1823172Y73958I141J142D01*
G01Y76185D01*
G02X1823231Y76327I200J0D01*
G01X1823235Y76331D01*
Y261552D01*
G02X1823294Y261694I200J0D01*
G01X1825941Y264341D01*
G02X1826083Y264400I142J-141D01*
G01X1859817D01*
G03X1859959Y264459I0J200D01*
G01X1862741Y267241D01*
G03X1862800Y267383I-141J142D01*
G01Y302617D01*
G03X1862741Y302759I-200J0D01*
G01X1855159Y310341D01*
G02X1855100Y310483I141J142D01*
G01Y315710D01*
G02X1855228Y315896I200J-1D01*
G03Y322530I-1271J3317D01*
G02X1855100Y322716I72J187D01*
G01Y325710D01*
G02X1855228Y325896I200J-1D01*
G03X1857509Y329213I-1271J3317D01*
G03X1857326Y330338I-3552J0D01*
G01X1857308Y330392D01*
X1857334Y330502D01*
X1857668Y330836D01*
X1857778Y330862D01*
X1857832Y330844D01*
G03X1858957Y330661I1125J3369D01*
G03Y337765I0J3552D01*
G03X1857832Y337582I0J-3552D01*
G01X1857778Y337564D01*
X1857668Y337590D01*
X1857334Y337924D01*
X1857308Y338034D01*
X1857326Y338088D01*
G03X1857509Y339213I-3369J1125D01*
G03X1857326Y340338I-3552J0D01*
G01X1857308Y340392D01*
X1857334Y340502D01*
X1857668Y340836D01*
X1857778Y340862D01*
X1857832Y340844D01*
G03X1858957Y340661I1125J3369D01*
G03Y347765I0J3552D01*
G03X1857832Y347582I0J-3552D01*
G01X1857778Y347564D01*
X1857668Y347590D01*
X1857334Y347924D01*
X1857308Y348034D01*
X1857326Y348088D01*
G03X1857509Y349213I-3369J1125D01*
G03X1855228Y352530I-3552J0D01*
G02X1855100Y352716I72J187D01*
G01Y353853D01*
G02X1855173Y354007I200J0D01*
G01X1855446Y354232D01*
X1855531Y354254D01*
X1855576Y354245D01*
G03Y366621I1196J6188D01*
G01X1855531Y366613D01*
X1855446Y366635D01*
X1855173Y366860D01*
G02X1855100Y367014I127J154D01*
G01Y393917D01*
G03X1855041Y394059I-200J0D01*
G01X1816159Y432941D01*
G03X1816017Y433000I-142J-141D01*
G01X1739183D01*
G03X1739041Y432941I0J-200D01*
G01X1698659Y392559D01*
G02X1698517Y392500I-142J141D01*
G01X1646183D01*
G02X1646041Y392559I0J200D01*
G01X1640542Y398058D01*
G02X1640483Y398200I141J142D01*
G01Y438858D01*
G03X1640424Y439000I-200J0D01*
G01Y582156D01*
G03X1640365Y582298I-200J0D01*
G01X1632801Y589862D01*
G03X1632659Y589921I-142J-141D01*
G01X1587359D01*
G02X1587217Y589980I0J200D01*
G01X1584816Y592381D01*
G02X1584757Y592523I141J142D01*
G01Y665850D01*
G02X1584816Y665992I200J0D01*
G01X1586271Y667447D01*
G02X1586413Y667506I142J-141D01*
G37*
G36*
G01X1639384Y107531D02*
G03X1638537Y107636I-851J-3397D01*
G03X1635035Y104134I0J-3502D01*
G03X1635140Y103287I3501J4D01*
G01Y103285D01*
X1635141Y103282D01*
G02X1635087Y103095I-195J-45D01*
G01X1631652Y99660D01*
G02X1631511Y99602I-141J142D01*
G01X1627819D01*
G02X1627678Y99660I0J200D01*
G01X1623684Y103654D01*
G02X1623625Y103795I141J142D01*
G01Y108539D01*
G02X1623682Y108679I200J0D01*
G01X1623683Y108680D01*
X1625984Y110981D01*
G03X1626043Y111123I-141J142D01*
G01Y111832D01*
G02X1626058Y111907I200J-1D01*
G01X1626387Y112719D01*
G03X1626402Y112794I-185J76D01*
G01Y119718D01*
G03X1626068Y121018I-2702J-1D01*
G02X1626043Y121114I175J97D01*
G01Y124057D01*
G03X1625984Y124199I-200J0D01*
G01X1623242Y126941D01*
G03X1623147Y126994I-141J-141D01*
G01X1623120Y127001D01*
X1623073Y127027D01*
X1605659Y144441D01*
X1605630Y144469D01*
X1605600Y144543D01*
Y175417D01*
G02X1605657Y175557I200J0D01*
G01X1605658Y175558D01*
X1619842Y189742D01*
G02X1619854Y189753I141J-142D01*
G01X1619855Y189754D01*
G02X1620071Y189781I129J-153D01*
G01X1620469Y189588D01*
X1620530Y189475D01*
X1620522Y189412D01*
G03X1620498Y189003I3478J-409D01*
G01Y189000D01*
G03X1624000Y192502I3502J0D01*
G01X1623997D01*
G03X1623588Y192478I0J-3502D01*
G01X1623525Y192470D01*
X1623412Y192531D01*
X1623219Y192929D01*
G02X1623252Y193152I180J87D01*
G01X1623255Y193155D01*
X1639841Y209741D01*
G03X1639900Y209883I-141J142D01*
G01Y381317D01*
G02X1639957Y381457I200J0D01*
G01X1639958Y381458D01*
X1645841Y387341D01*
G02X1645843Y387343I142J-140D01*
G02X1645983Y387400I140J-143D01*
G01X1699917D01*
G03X1700059Y387459I0J200D01*
G01X1742041Y429441D01*
G02X1742043Y429443I142J-140D01*
G02X1742183Y429500I140J-143D01*
G01X1814517D01*
G02X1814657Y429443I0J-200D01*
G01X1814658Y429442D01*
X1840791Y403309D01*
G02X1840793Y403307I-140J-142D01*
G02X1840850Y403167I-143J-140D01*
G01Y357833D01*
G03X1840909Y357691I200J0D01*
G01X1848441Y350159D01*
X1848471Y350069D01*
X1848464Y350022D01*
G03X1848405Y349216I5493J-807D01*
G01Y349213D01*
G03X1850945Y344549I5552J0D01*
G01X1850989Y344521D01*
X1851037Y344433D01*
Y343993D01*
X1850989Y343905D01*
X1850945Y343877D01*
G03X1849293Y342225I3012J-4664D01*
G01X1849265Y342181D01*
X1849177Y342133D01*
X1848737D01*
X1848649Y342181D01*
X1848621Y342225D01*
G03X1843957Y344765I-4664J-3012D01*
G03X1838405Y339213I0J-5552D01*
G03X1843207Y333712I5552J0D01*
G01X1843240Y333707D01*
X1843298Y333678D01*
X1843422Y333554D01*
X1843451Y333496D01*
X1843456Y333463D01*
G03X1845945Y329549I5501J750D01*
G01X1845988Y329521D01*
X1846037Y329432D01*
Y328994D01*
X1845988Y328905D01*
X1845945Y328877D01*
G03X1843456Y324963I3012J-4664D01*
G01X1843451Y324930D01*
X1843422Y324872D01*
X1843298Y324748D01*
X1843240Y324719D01*
X1843207Y324714D01*
G03Y313712I750J-5501D01*
G01X1843240Y313707D01*
X1843298Y313678D01*
X1843422Y313554D01*
X1843451Y313496D01*
X1843456Y313463D01*
G03X1843572Y312864I5500J754D01*
G01X1843585Y312812D01*
X1843557Y312711D01*
X1841661Y310815D01*
G02X1841636Y310794I-141J142D01*
G01X1841635Y310793D01*
G02X1841519Y310756I-116J163D01*
G01X1797829D01*
G02X1797709Y310796I0J200D01*
G03X1795601Y311502I-2109J-2796D01*
G01X1795600D01*
G03X1792680Y309933I0J-3502D01*
G01X1792666Y309912D01*
X1792630Y309880D01*
X1792530Y309825D01*
G02X1792434Y309800I-97J175D01*
G01X1779783D01*
G02X1779641Y309859I0J200D01*
G01X1775659Y313841D01*
G03X1775517Y313900I-142J-141D01*
G01X1774083D01*
G03X1773941Y313841I0J-200D01*
G01X1772959Y312859D01*
G03X1772900Y312717I141J-142D01*
G01Y309183D01*
G02X1772841Y309041I-200J0D01*
G01X1771260Y307460D01*
G02X1771119Y307402I-141J142D01*
G01X1726582D01*
G03X1726496Y307400I20J-2702D01*
G01X1724583D01*
G03X1724441Y307341I0J-200D01*
G01X1718659Y301559D01*
G03X1718600Y301417I141J-142D01*
G01Y223083D01*
G02X1718541Y222941I-200J0D01*
G01X1704135Y208535D01*
G02X1703940Y208483I-142J141D01*
G01X1703884Y208499D01*
X1703862Y208512D01*
G03X1702076Y209002I-1787J-3012D01*
G01X1702075D01*
G03X1698573Y205500I0J-3502D01*
G01Y205499D01*
G03X1699076Y203691I3502J0D01*
G01X1699112Y203631D01*
X1699095Y203495D01*
X1685628Y190028D01*
G02X1685515Y189971I-142J141D01*
G01X1685512D01*
G03X1682504Y186963I463J-3471D01*
G01Y186960D01*
G02X1682447Y186847I-198J29D01*
G01X1678759Y183159D01*
G03X1678700Y183017I141J-142D01*
G01Y181720D01*
G02X1678641Y181579I-200J1D01*
G03X1678213Y181023I1909J-1912D01*
G01X1678200Y181000D01*
X1671059Y173859D01*
G03X1671000Y173717I141J-142D01*
G01Y146083D01*
G03X1671059Y145941I200J0D01*
G01X1676402Y140598D01*
X1676411Y140576D01*
X1676794Y140206D01*
G02X1676797Y140203I-140J-143D01*
G01X1677790Y139210D01*
G02X1677848Y139069I-142J-141D01*
G01Y118231D01*
G02X1677790Y118090I-200J0D01*
G01X1669559Y109859D01*
X1669531Y109830D01*
X1669457Y109800D01*
X1641875D01*
G03X1641733Y109741I0J-200D01*
G01X1639576Y107584D01*
G02X1639389Y107530I-142J141D01*
G01X1639386Y107531D01*
X1639384D01*
G37*
%LPC*%
G75*
G36*
G01X1435946Y10505D02*
G02X1438098Y14529I-4528J5009D01*
G01X1438089Y14470D01*
X1438139Y14362D01*
X1438491Y14142D01*
X1438517Y14125D01*
X1438598Y14103D01*
X1438643Y14111D01*
X1438686Y14118D01*
X1438723Y14143D01*
G02X1441417Y14975I2694J-3946D01*
G02X1436639Y10197I0J-4778D01*
G01Y10226D01*
G03X1436550Y10392I-200J0D01*
G01X1436523Y10410D01*
X1436150Y10576D01*
X1436101Y10573D01*
X1436045Y10570D01*
G02X1436002Y10541I-132J150D01*
G01X1435967Y10524D01*
X1435946Y10505D01*
G37*
G36*
G01X245395D02*
G02X247547Y14529I-4528J5009D01*
G01X247538Y14470D01*
X247588Y14362D01*
X247940Y14142D01*
X247966Y14125D01*
X248047Y14103D01*
X248092Y14111D01*
X248135Y14118D01*
X248172Y14143D01*
G02X250866Y14975I2694J-3946D01*
G02X246088Y10197I0J-4778D01*
G01Y10226D01*
G03X245999Y10392I-200J0D01*
G01X245972Y10410D01*
X245599Y10576D01*
X245550Y10573D01*
X245494Y10570D01*
G02X245451Y10541I-132J150D01*
G01X245416Y10524D01*
X245395Y10505D01*
G37*
G36*
G01X339081Y24202D02*
G02X340498Y24502I1418J-3202D01*
G01X340500D01*
G02X344002Y21000I0J-3502D01*
G01Y20998D01*
G02X343702Y19581I-3502J1D01*
G03Y19419I183J-81D01*
G02X344002Y18001I-3202J-1418D01*
G01Y17999D01*
G02X343702Y16581I-3502J0D01*
G03Y16419I183J-81D01*
G02X344002Y15002I-3202J-1418D01*
G01Y15000D01*
G02X340500Y11498I-3502J0D01*
G01X340498D01*
G02X339081Y11798I1J3502D01*
G03X338919I-81J-183D01*
G02X337501Y11498I-1418J3202D01*
G01X337499D01*
G02X336081Y11798I0J3502D01*
G03X335919I-81J-183D01*
G02X334501Y11498I-1418J3202D01*
G01X334499D01*
G02X333081Y11798I0J3502D01*
G03X332919I-81J-183D01*
G02X331501Y11498I-1418J3202D01*
G01X331499D01*
G02X330081Y11798I0J3502D01*
G03X329919I-81J-183D01*
G02X328501Y11498I-1418J3202D01*
G01X328499D01*
G02X327081Y11798I0J3502D01*
G03X326919I-81J-183D01*
G02X325502Y11498I-1418J3202D01*
G01X325500D01*
G02X321998Y15000I0J3502D01*
G01Y15002D01*
G02X322298Y16419I3502J-1D01*
G03Y16581I-183J81D01*
G02X321998Y17999I3202J1418D01*
G01Y18001D01*
G02X322298Y19419I3502J0D01*
G03Y19581I-183J81D01*
G02X321998Y20998I3202J1418D01*
G01Y21000D01*
G02X325500Y24502I3502J0D01*
G01X325502D01*
G02X326919Y24202I-1J-3502D01*
G03X327081I81J183D01*
G02X328499Y24502I1418J-3202D01*
G01X328501D01*
G02X329919Y24202I0J-3502D01*
G03X330081I81J183D01*
G02X331499Y24502I1418J-3202D01*
G01X331501D01*
G02X332919Y24202I0J-3502D01*
G03X333081I81J183D01*
G02X334499Y24502I1418J-3202D01*
G01X334501D01*
G02X335919Y24202I0J-3502D01*
G03X336081I81J183D01*
G02X337499Y24502I1418J-3202D01*
G01X337501D01*
G02X338919Y24202I0J-3502D01*
G03X339081I81J183D01*
G37*
G36*
G01X1410811Y24278D02*
G02X1412228Y24578I1418J-3202D01*
G01X1412230D01*
G02X1415732Y21076I0J-3502D01*
G01Y21074D01*
G02X1415432Y19657I-3502J1D01*
G03Y19495I183J-81D01*
G02X1415732Y18077I-3202J-1418D01*
G01Y18075D01*
G02X1415432Y16657I-3502J0D01*
G03Y16495I183J-81D01*
G02X1415732Y15078I-3202J-1418D01*
G01Y15076D01*
G02X1412230Y11574I-3502J0D01*
G01X1412228D01*
G02X1410811Y11874I1J3502D01*
G03X1410649I-81J-183D01*
G02X1409231Y11574I-1418J3202D01*
G01X1409229D01*
G02X1407811Y11874I0J3502D01*
G03X1407649I-81J-183D01*
G02X1406231Y11574I-1418J3202D01*
G01X1406229D01*
G02X1404811Y11874I0J3502D01*
G03X1404649I-81J-183D01*
G02X1403231Y11574I-1418J3202D01*
G01X1403229D01*
G02X1401811Y11874I0J3502D01*
G03X1401649I-81J-183D01*
G02X1400231Y11574I-1418J3202D01*
G01X1400229D01*
G02X1398811Y11874I0J3502D01*
G03X1398649I-81J-183D01*
G02X1397232Y11574I-1418J3202D01*
G01X1397230D01*
G02X1393728Y15076I0J3502D01*
G01Y15078D01*
G02X1394028Y16495I3502J-1D01*
G03Y16657I-183J81D01*
G02X1393728Y18075I3202J1418D01*
G01Y18077D01*
G02X1394028Y19495I3502J0D01*
G03Y19657I-183J81D01*
G02X1393728Y21074I3202J1418D01*
G01Y21076D01*
G02X1397230Y24578I3502J0D01*
G01X1397232D01*
G02X1398649Y24278I-1J-3502D01*
G03X1398811I81J183D01*
G02X1400229Y24578I1418J-3202D01*
G01X1400231D01*
G02X1401649Y24278I0J-3502D01*
G03X1401811I81J183D01*
G02X1403229Y24578I1418J-3202D01*
G01X1403231D01*
G02X1404649Y24278I0J-3502D01*
G03X1404811I81J183D01*
G02X1406229Y24578I1418J-3202D01*
G01X1406231D01*
G02X1407649Y24278I0J-3502D01*
G03X1407811I81J183D01*
G02X1409229Y24578I1418J-3202D01*
G01X1409231D01*
G02X1410649Y24278I0J-3502D01*
G03X1410811I81J183D01*
G37*
G36*
G01X1228523Y39328D02*
G03X1228680Y39405I-1J200D01*
G02X1229866Y39985I1186J-923D01*
G02Y36979I0J-1503D01*
G02X1228680Y37559I0J1503D01*
G03X1228523Y37636I-158J-123D01*
G01X1228209D01*
G03X1228052Y37559I1J-200D01*
G02X1225680I-1186J923D01*
G03X1225523Y37636I-158J-123D01*
G01X1225209D01*
G03X1225052Y37559I1J-200D01*
G02X1222680I-1186J923D01*
G03X1222523Y37636I-158J-123D01*
G01X1222209D01*
G03X1222052Y37559I1J-200D01*
G02X1220866Y36979I-1186J923D01*
G02Y39985I0J1503D01*
G02X1222052Y39405I0J-1503D01*
G03X1222209Y39328I158J123D01*
G01X1222523D01*
G03X1222680Y39405I-1J200D01*
G02X1225052I1186J-923D01*
G03X1225209Y39328I158J123D01*
G01X1225523D01*
G03X1225680Y39405I-1J200D01*
G02X1228052I1186J-923D01*
G03X1228209Y39328I158J123D01*
G01X1228523D01*
G37*
G36*
G01X1268551Y39407D02*
G03X1269181I315J246D01*
G02X1270366Y39985I1185J-926D01*
G02Y36979I0J-1503D01*
G02X1269181Y37557I0J1504D01*
G03X1268551I-315J-246D01*
G02X1266181I-1185J926D01*
G03X1265551I-315J-246D01*
G02X1263181I-1185J926D01*
G03X1262551I-315J-246D01*
G02X1261366Y36979I-1185J926D01*
G02Y39985I0J1503D01*
G02X1262551Y39407I0J-1504D01*
G03X1263181I315J246D01*
G02X1265551I1185J-926D01*
G03X1266181I315J246D01*
G02X1268551I1185J-926D01*
G37*
G36*
G01X1314551D02*
G03X1315181I315J246D01*
G02X1316366Y39985I1185J-926D01*
G02Y36979I0J-1503D01*
G02X1315181Y37557I0J1504D01*
G03X1314551I-315J-246D01*
G02X1312181I-1185J926D01*
G03X1311551I-315J-246D01*
G02X1309181I-1185J926D01*
G03X1308551I-315J-246D01*
G02X1307366Y36979I-1185J926D01*
G02Y39985I0J1503D01*
G02X1308551Y39407I0J-1504D01*
G03X1309181I315J246D01*
G02X1311551I1185J-926D01*
G03X1312181I315J246D01*
G02X1314551I1185J-926D01*
G37*
G36*
G01X1350967Y39739D02*
G03X1351124Y39816I-1J200D01*
G02X1353496I1186J-923D01*
G03X1353653Y39739I158J123D01*
G01X1353968D01*
G03X1354125Y39816I-1J200D01*
G02X1356495I1185J-923D01*
G03X1356652Y39739I158J123D01*
G01X1356968D01*
G03X1357125Y39816I-1J200D01*
G02X1358310Y40395I1185J-923D01*
G02Y37391I0J-1502D01*
G02X1357125Y37970I0J1502D01*
G03X1356968Y38047I-158J-123D01*
G01X1356652D01*
G03X1356495Y37970I1J-200D01*
G02X1354125I-1185J923D01*
G03X1353968Y38047I-158J-123D01*
G01X1353653D01*
G03X1353496Y37970I1J-200D01*
G02X1351124I-1186J923D01*
G03X1350967Y38047I-158J-123D01*
G01X1350653D01*
G03X1350496Y37970I1J-200D01*
G02X1349310Y37390I-1186J923D01*
G02Y40396I0J1503D01*
G02X1350496Y39816I0J-1503D01*
G03X1350653Y39739I158J123D01*
G01X1350967D01*
G37*
G36*
G01X1159551Y39907D02*
G03X1160181I315J246D01*
G02X1161366Y40485I1185J-926D01*
G02Y37479I0J-1503D01*
G02X1160181Y38057I0J1504D01*
G03X1159551I-315J-246D01*
G02X1157181I-1185J926D01*
G03X1156551I-315J-246D01*
G02X1154181I-1185J926D01*
G03X1153551I-315J-246D01*
G02X1152366Y37479I-1185J926D01*
G02Y40485I0J1503D01*
G02X1153551Y39907I0J-1504D01*
G03X1154181I315J246D01*
G02X1156551I1185J-926D01*
G03X1157181I315J246D01*
G02X1159551I1185J-926D01*
G37*
G36*
G01X1423968Y41327D02*
G03X1424125Y41404I-1J200D01*
G02X1425310Y41983I1185J-923D01*
G02Y38979I0J-1502D01*
G02X1424125Y39558I0J1502D01*
G03X1423968Y39635I-158J-123D01*
G01X1423652D01*
G03X1423495Y39558I1J-200D01*
G02X1421125I-1185J923D01*
G03X1420968Y39635I-158J-123D01*
G01X1420652D01*
G03X1420495Y39558I1J-200D01*
G02X1418125I-1185J923D01*
G03X1417968Y39635I-158J-123D01*
G01X1417652D01*
G03X1417495Y39558I1J-200D01*
G02X1416310Y38979I-1185J923D01*
G02Y41983I0J1502D01*
G02X1417495Y41404I0J-1502D01*
G03X1417652Y41327I158J123D01*
G01X1417968D01*
G03X1418125Y41404I-1J200D01*
G02X1420495I1185J-923D01*
G03X1420652Y41327I158J123D01*
G01X1420968D01*
G03X1421125Y41404I-1J200D01*
G02X1423495I1185J-923D01*
G03X1423652Y41327I158J123D01*
G01X1423968D01*
G37*
G36*
G01X1085158Y44346D02*
G03X1085315Y44423I-1J200D01*
G02X1086500Y45002I1185J-923D01*
G02X1088002Y43500I0J-1502D01*
G02X1087423Y42315I-1502J0D01*
G03X1087346Y42158I123J-158D01*
G01Y41842D01*
G03X1087423Y41685I200J1D01*
G02X1088002Y40500I-923J-1185D01*
G02X1086500Y38998I-1502J0D01*
G02X1085315Y39577I0J1502D01*
G03X1085158Y39654I-158J-123D01*
G01X1084842D01*
G03X1084685Y39577I1J-200D01*
G02X1082315I-1185J923D01*
G03X1082158Y39654I-158J-123D01*
G01X1081842D01*
G03X1081685Y39577I1J-200D01*
G02X1079315I-1185J923D01*
G03X1079158Y39654I-158J-123D01*
G01X1078842D01*
G03X1078685Y39577I1J-200D01*
G02X1076315I-1185J923D01*
G03X1076158Y39654I-158J-123D01*
G01X1075842D01*
G03X1075685Y39577I1J-200D01*
G02X1074500Y38998I-1185J923D01*
G02X1072998Y40500I0J1502D01*
G02X1073577Y41685I1502J0D01*
G03X1073654Y41842I-123J158D01*
G01Y42158D01*
G03X1073577Y42315I-200J-1D01*
G02X1072998Y43500I923J1185D01*
G02X1074500Y45002I1502J0D01*
G02X1075685Y44423I0J-1502D01*
G03X1075842Y44346I158J123D01*
G01X1076158D01*
G03X1076315Y44423I-1J200D01*
G02X1078685I1185J-923D01*
G03X1078842Y44346I158J123D01*
G01X1079158D01*
G03X1079315Y44423I-1J200D01*
G02X1081685I1185J-923D01*
G03X1081842Y44346I158J123D01*
G01X1082158D01*
G03X1082315Y44423I-1J200D01*
G02X1084685I1185J-923D01*
G03X1084842Y44346I158J123D01*
G01X1085158D01*
G37*
G36*
G01X1607758Y63346D02*
G03X1607915Y63423I-1J200D01*
G02X1609100Y64002I1185J-923D01*
G02Y60998I0J-1502D01*
G02X1607915Y61577I0J1502D01*
G03X1607758Y61654I-158J-123D01*
G01X1607442D01*
G03X1607285Y61577I1J-200D01*
G02X1606100Y60998I-1185J923D01*
G02Y64002I0J1502D01*
G02X1607285Y63423I0J-1502D01*
G03X1607442Y63346I158J123D01*
G01X1607758D01*
G37*
G36*
G01Y66846D02*
G03X1607915Y66923I-1J200D01*
G02X1609100Y67502I1185J-923D01*
G02Y64498I0J-1502D01*
G02X1607915Y65077I0J1502D01*
G03X1607758Y65154I-158J-123D01*
G01X1607442D01*
G03X1607285Y65077I1J-200D01*
G02X1606100Y64498I-1185J923D01*
G02Y67502I0J1502D01*
G02X1607285Y66923I0J-1502D01*
G03X1607442Y66846I158J123D01*
G01X1607758D01*
G37*
G36*
G01Y70346D02*
G03X1607915Y70423I-1J200D01*
G02X1609100Y71002I1185J-923D01*
G02Y67998I0J-1502D01*
G02X1607915Y68577I0J1502D01*
G03X1607758Y68654I-158J-123D01*
G01X1607442D01*
G03X1607285Y68577I1J-200D01*
G02X1606100Y67998I-1185J923D01*
G02Y71002I0J1502D01*
G02X1607285Y70423I0J-1502D01*
G03X1607442Y70346I158J123D01*
G01X1607758D01*
G37*
G36*
G01Y82846D02*
G03X1607915Y82923I-1J200D01*
G02X1609100Y83502I1185J-923D01*
G02Y80498I0J-1502D01*
G02X1607915Y81077I0J1502D01*
G03X1607758Y81154I-158J-123D01*
G01X1607442D01*
G03X1607285Y81077I1J-200D01*
G02X1606100Y80498I-1185J923D01*
G02Y83502I0J1502D01*
G02X1607285Y82923I0J-1502D01*
G03X1607442Y82846I158J123D01*
G01X1607758D01*
G37*
G36*
G01X1617458Y83546D02*
G03X1617615Y83623I-1J200D01*
G02X1618800Y84202I1185J-923D01*
G02X1620302Y82700I0J-1502D01*
G02X1619723Y81515I-1502J0D01*
G03X1619646Y81358I123J-158D01*
G01Y81042D01*
G03X1619723Y80885I200J1D01*
G02Y78515I-923J-1185D01*
G03X1619646Y78358I123J-158D01*
G01Y78042D01*
G03X1619723Y77885I200J1D01*
G02X1620302Y76700I-923J-1185D01*
G02X1618800Y75198I-1502J0D01*
G02X1617615Y75777I0J1502D01*
G03X1617458Y75854I-158J-123D01*
G01X1617142D01*
G03X1616985Y75777I1J-200D01*
G02X1615800Y75198I-1185J923D01*
G02X1614300Y76623I0J1502D01*
G01Y76777D01*
G02X1614877Y77885I1500J-77D01*
G03X1614954Y78042I-123J158D01*
G01Y78358D01*
G03X1614877Y78515I-200J-1D01*
G02X1614300Y79623I923J1185D01*
G01Y79777D01*
G02X1614877Y80885I1500J-77D01*
G03X1614954Y81042I-123J158D01*
G01Y81358D01*
G03X1614877Y81515I-200J-1D01*
G02X1614300Y82623I923J1185D01*
G01Y82777D01*
G02X1615800Y84202I1500J-77D01*
G02X1616985Y83623I0J-1502D01*
G03X1617142Y83546I158J123D01*
G01X1617458D01*
G37*
G36*
G01X1644298Y83198D02*
Y83200D01*
G02X1651302I3502J0D01*
G01Y83198D01*
G02X1651002Y81781I-3502J1D01*
G03Y81619I183J-81D01*
G02X1651302Y80201I-3202J-1418D01*
G01Y80199D01*
G02X1651002Y78781I-3502J0D01*
G03Y78619I183J-81D01*
G02X1651302Y77202I-3202J-1418D01*
G01Y77200D01*
G02X1644298I-3502J0D01*
G01Y77202D01*
G02X1644598Y78619I3502J-1D01*
G03Y78781I-183J81D01*
G02X1644298Y80199I3202J1418D01*
G01Y80201D01*
G02X1644598Y81619I3502J0D01*
G03Y81781I-183J81D01*
G02X1644298Y83198I3202J1418D01*
G37*
G36*
G01X1607758Y86346D02*
G03X1607915Y86423I-1J200D01*
G02X1609100Y87002I1185J-923D01*
G02Y83998I0J-1502D01*
G02X1607915Y84577I0J1502D01*
G03X1607758Y84654I-158J-123D01*
G01X1607442D01*
G03X1607285Y84577I1J-200D01*
G02X1606100Y83998I-1185J923D01*
G02Y87002I0J1502D01*
G02X1607285Y86423I0J-1502D01*
G03X1607442Y86346I158J123D01*
G01X1607758D01*
G37*
G36*
G01Y89846D02*
G03X1607915Y89923I-1J200D01*
G02X1609100Y90502I1185J-923D01*
G02Y87498I0J-1502D01*
G02X1607915Y88077I0J1502D01*
G03X1607758Y88154I-158J-123D01*
G01X1607442D01*
G03X1607285Y88077I1J-200D01*
G02X1606100Y87498I-1185J923D01*
G02Y90502I0J1502D01*
G02X1607285Y89923I0J-1502D01*
G03X1607442Y89846I158J123D01*
G01X1607758D01*
G37*
G36*
G01X1085158Y99846D02*
G03X1085315Y99923I-1J200D01*
G02X1086500Y100502I1185J-923D01*
G02X1088002Y99000I0J-1502D01*
G02X1087423Y97815I-1502J0D01*
G03X1087346Y97658I123J-158D01*
G01Y97342D01*
G03X1087423Y97185I200J1D01*
G02X1088002Y96000I-923J-1185D01*
G02X1086500Y94498I-1502J0D01*
G02X1085315Y95077I0J1502D01*
G03X1085158Y95154I-158J-123D01*
G01X1084842D01*
G03X1084685Y95077I1J-200D01*
G02X1082315I-1185J923D01*
G03X1082158Y95154I-158J-123D01*
G01X1081842D01*
G03X1081685Y95077I1J-200D01*
G02X1079315I-1185J923D01*
G03X1079158Y95154I-158J-123D01*
G01X1078842D01*
G03X1078685Y95077I1J-200D01*
G02X1076315I-1185J923D01*
G03X1076158Y95154I-158J-123D01*
G01X1075842D01*
G03X1075685Y95077I1J-200D01*
G02X1074500Y94498I-1185J923D01*
G02X1072998Y96000I0J1502D01*
G02X1073577Y97185I1502J0D01*
G03X1073654Y97342I-123J158D01*
G01Y97658D01*
G03X1073577Y97815I-200J-1D01*
G02X1072998Y99000I923J1185D01*
G02X1074500Y100502I1502J0D01*
G02X1075685Y99923I0J-1502D01*
G03X1075842Y99846I158J123D01*
G01X1076158D01*
G03X1076315Y99923I-1J200D01*
G02X1078685I1185J-923D01*
G03X1078842Y99846I158J123D01*
G01X1079158D01*
G03X1079315Y99923I-1J200D01*
G02X1081685I1185J-923D01*
G03X1081842Y99846I158J123D01*
G01X1082158D01*
G03X1082315Y99923I-1J200D01*
G02X1084685I1185J-923D01*
G03X1084842Y99846I158J123D01*
G01X1085158D01*
G37*
G36*
G01X1524600Y107998D02*
G02Y115002I0J3502D01*
G02X1528102Y111501I0J-3502D01*
G01Y111500D01*
G02X1527831Y110174I-3498J24D01*
G01X1527816Y110137D01*
Y109982D01*
G03X1527825Y109922I200J-1D01*
G01X1527855Y109828D01*
X1527896Y109774D01*
X1527925Y109755D01*
G02X1528602Y108500I-825J-1255D01*
G02X1527100Y106998I-1502J0D01*
G02X1525722Y107904I0J1501D01*
G01X1525718Y107914D01*
G03X1525675Y107977I-184J-79D01*
G01X1525648Y108004D01*
X1525518Y108067D01*
G03X1525431Y108087I-87J-180D01*
G01X1525383D01*
X1525347Y108080D01*
X1525344D01*
X1525323Y108076D01*
G02X1524600Y107998I-735J3423D01*
G37*
G36*
G01X1490103Y114698D02*
G03X1490733I315J246D01*
G02X1491918Y115276I1185J-926D01*
G02X1493421Y113773I0J-1503D01*
G02X1492843Y112588I-1504J0D01*
G03Y111958I246J-315D01*
G02Y109588I-926J-1185D01*
G03Y108958I246J-315D01*
G02Y106588I-926J-1185D01*
G03Y105958I246J-315D01*
G02X1493421Y104773I-926J-1185D01*
G02X1491918Y103270I-1503J0D01*
G02X1490733Y103848I0J1504D01*
G03X1490103I-315J-246D01*
G02X1487733I-1185J926D01*
G03X1487103I-315J-246D01*
G02X1484733I-1185J926D01*
G03X1484103I-315J-246D01*
G02X1482918Y103270I-1185J926D01*
G02X1481415Y104773I0J1503D01*
G02X1481993Y105958I1504J0D01*
G03Y106588I-246J315D01*
G02Y108958I926J1185D01*
G03Y109588I-246J315D01*
G02Y111958I926J1185D01*
G03Y112588I-246J315D01*
G02X1481415Y113773I926J1185D01*
G02X1482918Y115276I1503J0D01*
G02X1484103Y114698I0J-1504D01*
G03X1484733I315J246D01*
G02X1487103I1185J-926D01*
G03X1487733I315J246D01*
G02X1490103I1185J-926D01*
G37*
G36*
G01X1683500Y132923D02*
Y133077D01*
G02X1685000Y134502I1500J-77D01*
G02Y131498I0J-1502D01*
G02X1683500Y132923I0J1502D01*
G37*
G36*
G01X1691100Y135898D02*
Y136052D01*
G02X1692600Y137477I1500J-77D01*
G02Y134473I0J-1502D01*
G02X1691100Y135898I0J1502D01*
G37*
G36*
G01X1705598Y142499D02*
Y142501D01*
G02X1707100Y144002I1502J-1D01*
G02Y140998I0J-1502D01*
G02X1707020Y141000I-2J1502D01*
G01X1707018D01*
G03X1706868Y140942I-9J-200D01*
G01X1706659Y140733D01*
G03X1706600Y140591I141J-142D01*
G01Y140528D01*
X1706601Y140520D01*
G02X1706602Y140501I-1498J-88D01*
G01Y140499D01*
G02X1705100Y138998I-1502J1D01*
G02Y142002I0J1502D01*
G02X1705180Y142000I2J-1502D01*
G01X1705182D01*
G03X1705332Y142058I9J200D01*
G01X1705541Y142267D01*
G03X1705600Y142409I-141J142D01*
G01Y142472D01*
X1705599Y142480D01*
G02X1705598Y142499I1498J88D01*
G37*
G36*
G01X1684474Y148000D02*
G02X1685526Y149433I1502J0D01*
G02X1686426I450J-1433D01*
G02X1687478Y148000I-450J-1433D01*
G01Y147997D01*
G02X1687411Y147555I-1502J2D01*
G03X1687857Y147042I382J-118D01*
G02X1688100Y147062I244J-1482D01*
G02X1686598Y145560I0J-1502D01*
G01Y145563D01*
G02X1686665Y146005I1502J-2D01*
G03X1686219Y146518I-382J118D01*
G02X1685976Y146498I-244J1482D01*
G02X1684474Y148000I0J1502D01*
G37*
G36*
G01X1685976Y162998D02*
G02X1687478Y164500I0J1502D01*
G01Y164497D01*
G02X1687411Y164055I-1502J2D01*
G03X1687857Y163542I382J-118D01*
G02X1688100Y163562I244J-1482D01*
G02X1686598Y162060I0J-1502D01*
G01Y162063D01*
G02X1686665Y162505I1502J-2D01*
G03X1686219Y163018I-382J118D01*
G02X1685976Y162998I-244J1482D01*
G37*
G36*
G01Y173997D02*
G02X1687479Y175500I0J1503D01*
G01Y175497D01*
G02X1687411Y175056I-1503J6D01*
G01X1687409Y175051D01*
X1687402Y175022D01*
X1687397Y174994D01*
G03X1687578Y174599I396J-58D01*
G03X1687804Y174537I214J338D01*
G03X1687833Y174540I-6J200D01*
G02X1688095Y174563I262J-1480D01*
G01X1688100D01*
G02X1686597Y173060I0J-1503D01*
G01Y173063D01*
G02X1686665Y173504I1503J-6D01*
G01X1686667Y173509D01*
X1686674Y173538D01*
X1686679Y173566D01*
G03X1686498Y173961I-396J58D01*
G03X1686272Y174023I-214J-338D01*
G03X1686243Y174020I6J-200D01*
G02X1685981Y173997I-262J1480D01*
G01X1685976D01*
G37*
G36*
G01X1771822Y176014D02*
G02X1771097Y177300I778J1286D01*
G02X1774103I1503J0D01*
G02X1773293Y175966I-1503J0D01*
G03X1773277Y175957I90J-179D01*
G03X1773285Y175280I217J-336D01*
G02X1774002Y174000I-784J-1280D01*
G02X1770998I-1502J0D01*
G02X1771794Y175326I1502J0D01*
G03X1771858Y175989I-188J353D01*
G01X1771843Y176001D01*
X1771830Y176009D01*
X1771827Y176011D01*
X1771822Y176014D01*
G37*
G36*
G01X1724800Y206777D02*
G02X1724823Y206778I77J-1499D01*
G01X1724824D01*
G02X1726326Y205276I0J-1502D01*
G02X1724826Y203774I-1502J0D01*
G01X1724743Y203776D01*
G02X1723571Y204447I81J1501D01*
G03X1722872Y204389I-334J-220D01*
G02X1721500Y203498I-1372J611D01*
G02Y206502I0J1502D01*
G02X1722753Y205829I0J-1503D01*
G03X1723452Y205887I334J220D01*
G02X1724745Y206776I1372J-611D01*
G01X1724793D01*
X1724800Y206777D01*
G37*
G36*
G01X1739468Y239513D02*
G02X1739098Y240500I1131J987D01*
G02X1742102I1502J0D01*
G02X1741732Y239513I-1501J0D01*
G01X1741708Y239485D01*
X1741683Y239419D01*
Y239081D01*
X1741708Y239015D01*
X1741732Y238987D01*
G02Y237013I-1131J-987D01*
G01X1741708Y236985D01*
X1741683Y236919D01*
Y236581D01*
X1741708Y236515D01*
X1741732Y236487D01*
G02Y234513I-1131J-987D01*
G01X1741708Y234485D01*
X1741683Y234419D01*
Y234081D01*
X1741708Y234015D01*
X1741732Y233987D01*
G02X1742102Y233000I-1131J-987D01*
G02X1739098I-1502J0D01*
G02X1739468Y233987I1501J0D01*
G01X1739492Y234015D01*
X1739517Y234081D01*
Y234419D01*
X1739492Y234485D01*
X1739468Y234513D01*
G02Y236487I1131J987D01*
G01X1739492Y236515D01*
X1739517Y236581D01*
Y236919D01*
X1739492Y236985D01*
X1739468Y237013D01*
G02Y238987I1131J987D01*
G01X1739492Y239015D01*
X1739517Y239081D01*
Y239419D01*
X1739492Y239485D01*
X1739468Y239513D01*
G37*
G36*
G01X1750468D02*
G02X1750098Y240500I1131J987D01*
G02X1753102I1502J0D01*
G02X1752732Y239513I-1501J0D01*
G01X1752708Y239485D01*
X1752683Y239419D01*
Y239081D01*
X1752708Y239015D01*
X1752732Y238987D01*
G02Y237013I-1131J-987D01*
G01X1752708Y236985D01*
X1752683Y236919D01*
Y236581D01*
X1752708Y236515D01*
X1752732Y236487D01*
G02Y234513I-1131J-987D01*
G01X1752708Y234485D01*
X1752683Y234419D01*
Y234081D01*
X1752708Y234015D01*
X1752732Y233987D01*
G02X1753102Y233000I-1131J-987D01*
G02X1750098I-1502J0D01*
G02X1750468Y233987I1501J0D01*
G01X1750492Y234015D01*
X1750517Y234081D01*
Y234419D01*
X1750492Y234485D01*
X1750468Y234513D01*
G02Y236487I1131J987D01*
G01X1750492Y236515D01*
X1750517Y236581D01*
Y236919D01*
X1750492Y236985D01*
X1750468Y237013D01*
G02Y238987I1131J987D01*
G01X1750492Y239015D01*
X1750517Y239081D01*
Y239419D01*
X1750492Y239485D01*
X1750468Y239513D01*
G37*
G36*
G01X1765524Y241613D02*
G02X1764945Y242798I923J1185D01*
G02X1767949I1502J0D01*
G02X1767370Y241613I-1502J0D01*
G03X1767293Y241456I123J-158D01*
G01Y241140D01*
G03X1767370Y240983I200J1D01*
G02X1767949Y239798I-923J-1185D01*
G02X1764945I-1502J0D01*
G02X1765524Y240983I1502J0D01*
G03X1765601Y241140I-123J158D01*
G01Y241456D01*
G03X1765524Y241613I-200J-1D01*
G37*
G36*
G01X1774524D02*
G02X1773945Y242798I923J1185D01*
G02X1776949I1502J0D01*
G02X1776370Y241613I-1502J0D01*
G03X1776293Y241456I123J-158D01*
G01Y241140D01*
G03X1776370Y240983I200J1D01*
G02X1776949Y239798I-923J-1185D01*
G02X1773945I-1502J0D01*
G02X1774524Y240983I1502J0D01*
G03X1774601Y241140I-123J158D01*
G01Y241456D01*
G03X1774524Y241613I-200J-1D01*
G37*
G36*
G01X1783024D02*
G02X1782445Y242798I923J1185D01*
G02X1785449I1502J0D01*
G02X1784870Y241613I-1502J0D01*
G03X1784793Y241456I123J-158D01*
G01Y241140D01*
G03X1784870Y240983I200J1D01*
G02X1785449Y239798I-923J-1185D01*
G02X1782445I-1502J0D01*
G02X1783024Y240983I1502J0D01*
G03X1783101Y241140I-123J158D01*
G01Y241456D01*
G03X1783024Y241613I-200J-1D01*
G37*
G36*
G01X695185Y327292D02*
G03X695332I73J186D01*
G02X696613Y327535I1282J-3260D01*
G02Y320529I0J-3503D01*
G02X695332Y320772I1J3503D01*
G03X695185I-73J-186D01*
G02X693904Y320529I-1282J3260D01*
G02Y327535I0J3503D01*
G02X695185Y327292I-1J-3503D01*
G37*
G36*
G01X717401Y328493D02*
G02X718904Y329996I0J1503D01*
G02Y329988I-1503J-4D01*
G03X719331Y329587I400J-2D01*
G02X719433Y329590I95J-1500D01*
G02X717930Y328087I0J-1503D01*
G02Y328095I1503J4D01*
G03X717503Y328496I-400J2D01*
G02X717401Y328493I-95J1500D01*
G37*
G36*
G01X883763Y381000D02*
G02X884513Y382300I1502J0D01*
G02X886017I752J-1299D01*
G02X886767Y381000I-752J-1300D01*
G02X883763I-1502J0D01*
G37*
G36*
G01X906372Y378435D02*
G02X903098Y382200I528J3765D01*
G02X906900Y378398I3802J0D01*
G02X906372Y378435I1J3802D01*
G37*
G36*
G01X637653Y262746D02*
G02X637182Y264500I3030J1754D01*
G02X637903Y266628I3501J0D01*
G03Y266872I-159J122D01*
G02X637182Y269000I2780J2128D01*
G02X644186I3502J0D01*
G02X643465Y266872I-3501J0D01*
G03Y266628I159J-122D01*
G02X644186Y264500I-2780J-2128D01*
G02X644014Y263416I-3502J0D01*
G03X644031Y263254I190J-62D01*
G02X644502Y261500I-3030J-1754D01*
G02X637498I-3502J0D01*
G02X637670Y262584I3502J0D01*
G03X637653Y262746I-190J62D01*
G37*
G36*
G01X657181Y240902D02*
G02X658598Y241202I1418J-3202D01*
G01X658600D01*
G02Y234198I0J-3502D01*
G01X658598D01*
G02X657181Y234498I1J3502D01*
G03X657019I-81J-183D01*
G02X655602Y234198I-1418J3202D01*
G01X655600D01*
G02Y241202I0J3502D01*
G01X655602D01*
G02X657019Y240902I-1J-3502D01*
G03X657181I81J183D01*
G37*
G36*
G01X604817Y258285D02*
G02X604198Y259500I883J1215D01*
G02X607202I1502J0D01*
G02X606662Y258346I-1503J0D01*
G01X606661D01*
G03X606590Y258185I129J-153D01*
G01X606600Y257870D01*
G03X606682Y257716I200J8D01*
G01X606683Y257715D01*
G02X607302Y256500I-883J-1215D01*
G02X604298I-1502J0D01*
G02X604838Y257654I1503J0D01*
G01X604839D01*
G03X604910Y257815I-129J153D01*
G01X604900Y258130D01*
G03X604818Y258284I-200J-8D01*
G01X604817Y258285D01*
G37*
G36*
G01X676184Y272498D02*
G02Y275502I0J1502D01*
G02X677594Y274517I0J-1502D01*
G03X678225Y274346I376J137D01*
G02X679184Y274692I959J-1156D01*
G02Y271688I0J-1502D01*
G02X677774Y272673I0J1502D01*
G03X677143Y272844I-376J-137D01*
G02X676184Y272498I-959J1156D01*
G37*
G36*
G01X588042Y280211D02*
X588009Y280240D01*
G02X586796Y282890I2288J2650D01*
G02X593800I3502J0D01*
G02X592587Y280240I-3501J0D01*
G01X592554Y280211D01*
X592518Y280133D01*
Y279741D01*
X592554Y279663D01*
X592587Y279634D01*
G02X593800Y276984I-2288J-2650D01*
G02X586796I-3502J0D01*
G02X588009Y279634I3501J0D01*
G01X588042Y279663D01*
X588078Y279741D01*
Y280133D01*
X588042Y280211D01*
G37*
G36*
G01X702984Y279998D02*
G02Y287002I0J3502D01*
G02X704734Y286533I-1J-3502D01*
G01X704757Y286520D01*
X704807Y286506D01*
X704861D01*
X704911Y286520D01*
X704934Y286533D01*
G02X706684Y287002I1751J-3033D01*
G02Y279998I0J-3502D01*
G02X704934Y280467I1J3502D01*
G01X704911Y280480D01*
X704861Y280494D01*
X704807D01*
X704757Y280480D01*
X704734Y280467D01*
G02X702984Y279998I-1751J3033D01*
G37*
G36*
G01X568413Y290812D02*
X568399Y290833D01*
G02X567823Y292757I2925J1924D01*
G02X574827I3502J0D01*
G02X574456Y291189I-3502J1D01*
G01X574443Y291163D01*
X574433Y291108D01*
X574438Y291054D01*
X574454Y291010D01*
X574468Y290989D01*
G02X575044Y289065I-2925J-1924D01*
G02X568040I-3502J0D01*
G02X568411Y290633I3502J-1D01*
G01X568424Y290659D01*
X568434Y290714D01*
X568429Y290768D01*
X568413Y290812D01*
G37*
G36*
G01X567539Y305137D02*
X567892Y305144D01*
X567962Y305174D01*
X567990Y305201D01*
G02X570443Y306204I2453J-2498D01*
G02Y299200I0J-3502D01*
G02X568094Y300105I0J3501D01*
G01X568066Y300130D01*
X567995Y300157D01*
X567642Y300150D01*
X567572Y300120D01*
X567544Y300093D01*
G02X565091Y299090I-2453J2498D01*
G02Y306094I0J3502D01*
G02X567440Y305189I0J-3501D01*
G01X567468Y305164D01*
X567539Y305137D01*
G37*
G36*
G01X1140158Y346654D02*
X1139842D01*
G03X1139685Y346577I1J-200D01*
G02X1138500Y345998I-1185J923D01*
G02Y349002I0J1502D01*
G02X1139685Y348423I0J-1502D01*
G03X1139842Y348346I158J123D01*
G01X1140158D01*
G03X1140315Y348423I-1J200D01*
G02X1141500Y349002I1185J-923D01*
G02Y345998I0J-1502D01*
G02X1140315Y346577I0J1502D01*
G03X1140158Y346654I-158J-123D01*
G37*
G36*
G01X1067401Y230167D02*
X1067799D01*
X1067879Y230205D01*
X1067908Y230239D01*
G02X1070600Y231502I2693J-2239D01*
G02X1072019Y231202I1J-3502D01*
G03X1072181I81J182D01*
G02X1073600Y231502I1418J-3202D01*
G02Y224498I0J-3502D01*
G02X1072181Y224798I-1J3502D01*
G03X1072019I-81J-182D01*
G02X1070600Y224498I-1418J3202D01*
G02X1067908Y225761I1J3502D01*
G01X1067879Y225795D01*
X1067799Y225833D01*
X1067401D01*
X1067321Y225795D01*
X1067292Y225761D01*
G02X1064600Y224498I-2693J2239D01*
G02X1063181Y224798I-1J3502D01*
G03X1063019I-81J-182D01*
G02X1061600Y224498I-1418J3202D01*
G02Y231502I0J3502D01*
G02X1063019Y231202I1J-3502D01*
G03X1063181I81J182D01*
G02X1064600Y231502I1418J-3202D01*
G02X1067292Y230239I-1J-3502D01*
G01X1067321Y230205D01*
X1067401Y230167D01*
G37*
G36*
G01X1057550Y271533D02*
G02X1059300Y272002I1751J-3033D01*
G02Y264998I0J-3502D01*
G02X1057550Y265467I1J3502D01*
G03X1057350I-100J-174D01*
G02X1055600Y264998I-1751J3033D01*
G02Y272002I0J3502D01*
G02X1057350Y271533I-1J-3502D01*
G03X1057550I100J174D01*
G37*
G36*
G01X1169766Y271867D02*
Y272259D01*
X1169731Y272337D01*
X1169697Y272366D01*
G02X1168484Y275016I2288J2650D01*
G02X1175488I3502J0D01*
G02X1174275Y272366I-3501J0D01*
G01X1174241Y272337D01*
X1174206Y272259D01*
Y271867D01*
X1174241Y271789D01*
X1174275Y271760D01*
G02X1175488Y269110I-2288J-2650D01*
G02X1168484I-3502J0D01*
G02X1169697Y271760I3501J0D01*
G01X1169731Y271789D01*
X1169766Y271867D01*
G37*
G36*
G01X1199059Y290701D02*
X1198941D01*
G03X1198810Y290652I0J-200D01*
G02X1196500Y289782I-2310J2632D01*
G02Y296786I0J3502D01*
G02X1198810Y295916I0J-3502D01*
G03X1198941Y295867I131J151D01*
G01X1199059D01*
G03X1199190Y295916I0J200D01*
G02X1201500Y296786I2310J-2632D01*
G02Y289782I0J-3502D01*
G02X1199190Y290652I0J3502D01*
G03X1199059Y290701I-131J-151D01*
G37*
G36*
G01X1155655Y293721D02*
X1155645Y294117D01*
X1155606Y294195D01*
X1155571Y294223D01*
G02X1155007Y295396I938J1173D01*
G02X1158011I1502J0D01*
G02X1157506Y294273I-1501J0D01*
G01X1157472Y294243D01*
X1157438Y294163D01*
X1157448Y293767D01*
X1157487Y293689D01*
X1157522Y293661D01*
G02X1158086Y292488I-938J-1173D01*
G02X1155082I-1502J0D01*
G02X1155587Y293611I1501J0D01*
G01X1155621Y293641D01*
X1155655Y293721D01*
G37*
G36*
G01X1174781Y319702D02*
G02X1176200Y320002I1418J-3202D01*
G02Y312998I0J-3502D01*
G02X1174781Y313298I-1J3502D01*
G03X1174619I-81J-182D01*
G02X1173200Y312998I-1418J3202D01*
G02Y320002I0J3502D01*
G02X1174619Y319702I1J-3502D01*
G03X1174781I81J182D01*
G37*
G36*
G01X1197327Y317802D02*
X1197586Y318110D01*
X1197608Y318197D01*
X1197600Y318242D01*
G02X1197535Y318912I3437J672D01*
G02X1201037Y315410I3502J0D01*
G02X1200965Y315411I13J3502D01*
G01X1200919Y315412D01*
X1200837Y315374D01*
X1200578Y315066D01*
X1200556Y314979D01*
X1200564Y314934D01*
G02X1200629Y314264I-3437J-672D01*
G02X1197127Y317766I-3502J0D01*
G02X1197199Y317765I-13J-3502D01*
G01X1197245Y317764D01*
X1197327Y317802D01*
G37*
G36*
G01X1130484Y267326D02*
G02X1130474Y267500I1492J173D01*
G02X1131976Y265998I1502J0D01*
G02X1131750Y266015I-1J1502D01*
G03X1131292Y265574I-61J-395D01*
G02X1131302Y265400I-1492J-173D01*
G02X1129800Y266902I-1502J0D01*
G02X1130026Y266885I1J-1502D01*
G03X1130484Y267326I61J395D01*
G37*
G36*
G01X1083578Y271596D02*
G02X1083100Y271518I-478J1424D01*
G02X1084602Y273020I0J1502D01*
G02X1084596Y272888I-1502J2D01*
G03X1085122Y272474I398J-35D01*
G02X1085600Y272552I478J-1424D01*
G02X1084098Y271050I0J-1502D01*
G02X1084104Y271182I1502J-2D01*
G03X1083578Y271596I-398J35D01*
G37*
G36*
G01X1084059Y277654D02*
G02X1083100Y277308I-959J1156D01*
G02Y280312I0J1502D01*
G02X1084510Y279327I0J-1502D01*
G03X1085141Y279156I376J137D01*
G02X1086100Y279502I959J-1156D01*
G02Y276498I0J-1502D01*
G02X1084690Y277483I0J1502D01*
G03X1084059Y277654I-376J-137D01*
G37*
G36*
G01X1071859Y292493D02*
G02X1073339Y293741I1480J-254D01*
G02Y290737I0J-1502D01*
G02X1072570Y290949I0J1501D01*
G03X1071970Y290673I-206J-343D01*
G02X1070490Y289425I-1480J254D01*
G02Y292429I0J1502D01*
G02X1071259Y292217I0J-1501D01*
G03X1071859Y292493I206J343D01*
G37*
G36*
G01X1068269Y303138D02*
G02X1067025Y302478I-1244J842D01*
G02Y305482I0J1502D01*
G02X1068269Y304822I0J-1502D01*
G03X1068931I331J224D01*
G02X1070175Y305482I1244J-842D01*
G02Y302478I0J-1502D01*
G02X1068931Y303138I0J1502D01*
G03X1068269I-331J-224D01*
G37*
G36*
G01X1129258Y306891D02*
G02X1129008Y307720I1253J830D01*
G02X1132012I1502J0D01*
G02X1131439Y306538I-1504J-1D01*
G01X1131438D01*
X1131436Y306537D01*
G03X1131364Y306412I126J-156D01*
G01X1131321Y306146D01*
G03X1131351Y306004I197J-32D01*
G01X1131352Y306003D01*
G02X1131602Y305174I-1253J-830D01*
G02X1128598I-1502J0D01*
G02X1129171Y306356I1504J1D01*
G01X1129172D01*
X1129174Y306357D01*
G03X1129246Y306482I-126J156D01*
G01X1129289Y306748D01*
G03X1129259Y306890I-197J32D01*
G01X1129258Y306891D01*
G37*
G36*
G01X1106886Y289884D02*
G02X1108100Y290502I1214J-883D01*
G02Y287498I0J-1502D01*
G02X1106886Y288116I0J1501D01*
G03X1106239I-324J-236D01*
G02X1105025Y287498I-1214J883D01*
G02Y290502I0J1502D01*
G02X1106239Y289884I0J-1501D01*
G03X1106886I324J236D01*
G37*
G36*
G01X1103663Y311202D02*
G02X1105080Y310902I-1J-3502D01*
G03X1105242I81J183D01*
G02X1106659Y311202I1418J-3202D01*
G01X1106661D01*
G02Y304198I0J-3502D01*
G01X1106659D01*
G02X1105242Y304498I1J3502D01*
G03X1105080I-81J-183D01*
G02X1103663Y304198I-1418J3202D01*
G01X1103661D01*
G02Y311202I0J3502D01*
G01X1103663D01*
G37*
G36*
G01X1629627Y112077D02*
G02X1627821Y115140I1694J3063D01*
G02X1634825I3502J0D01*
G02X1633927Y112800I-3502J1D01*
G01Y112799D01*
X1633926Y112798D01*
G03X1633879Y112632I150J-132D01*
G01X1633930Y112323D01*
G03X1633966Y112239I197J35D01*
G03X1634028Y112183I162J117D01*
G01X1634031Y112181D01*
X1634032Y112180D01*
G02X1635838Y109117I-1694J-3063D01*
G02X1633460Y105800I-3502J0D01*
G01X1633422Y105787D01*
X1633364Y105736D01*
X1633220Y105451D01*
G03X1633208Y105301I179J-90D01*
G01Y105300D01*
G02X1633372Y104242I-3338J-1059D01*
G01Y104240D01*
G02X1626368I-3502J0D01*
G02X1628746Y107557I3502J0D01*
G01X1628784Y107570D01*
X1628842Y107621D01*
X1628986Y107906D01*
G03X1628998Y108056I-179J90D01*
G01Y108057D01*
G02X1628834Y109115I3338J1059D01*
G01Y109117D01*
G02X1629732Y111457I3502J-1D01*
G01Y111458D01*
X1629733Y111459D01*
G03X1629780Y111625I-150J132D01*
G01X1629729Y111934D01*
G03X1629693Y112018I-197J-35D01*
G03X1629631Y112074I-162J-117D01*
G01X1629628Y112076D01*
X1629627Y112077D01*
G37*
G36*
G01X1648296Y126834D02*
G02X1651325Y128578I3029J-1758D01*
G02X1652794Y128255I0J-3502D01*
G01X1652833Y128237D01*
X1652917Y128236D01*
X1653230Y128370D01*
G03X1653341Y128489I-78J184D01*
G01Y128490D01*
G02X1656657Y130867I3316J-1124D01*
G02Y123863I0J-3502D01*
G02X1655188Y124186I0J3502D01*
G01X1655149Y124204D01*
X1655065Y124205D01*
X1654752Y124071D01*
G03X1654641Y123952I78J-184D01*
G01Y123951D01*
G02X1654336Y123288I-3317J1124D01*
G03X1654318Y123124I172J-102D01*
G02X1654492Y122034I-3327J-1090D01*
G02X1650990Y118532I-3502J0D01*
G02X1649721Y118770I0J3502D01*
G03X1649551Y118758I-72J-186D01*
G02X1647837Y118310I-1714J3055D01*
G02X1644758Y120143I0J3502D01*
G01X1644737Y120182D01*
X1644665Y120235D01*
X1644274Y120312D01*
X1644188Y120290D01*
X1644153Y120261D01*
G02X1641932Y119467I-2221J2709D01*
G02X1638430Y122969I0J3502D01*
G02X1641865Y126470I3502J0D01*
G01X1641875D01*
G03X1642022Y126551I-14J200D01*
G03X1642026Y126557I-164J114D01*
G02X1644917Y128083I2891J-1975D01*
G01X1644918D01*
G02X1647640Y126783I-1J-3502D01*
G01X1647672Y126745D01*
X1647761Y126706D01*
X1648188Y126739D01*
X1648271Y126791D01*
X1648296Y126834D01*
G37*
G36*
G01X1624349Y158615D02*
G03X1624605Y158623I123J158D01*
G02X1626925Y159502I2320J-2622D01*
G02Y152498I0J-3502D01*
G02X1624681Y153312I1J3502D01*
G03X1624676Y153316I-127J-154D01*
G03X1624420Y153308I-123J-158D01*
G02X1622100Y152429I-2320J2622D01*
G02Y159433I0J3502D01*
G02X1624344Y158619I-1J-3502D01*
G03X1624349Y158615I127J154D01*
G37*
G36*
G01X1620615Y175533D02*
G02X1619598Y178000I2484J2467D01*
G02X1623100Y181502I3502J0D01*
G02X1626588Y178308I0J-3502D01*
G01X1626592Y178257D01*
X1626622Y178213D01*
G03X1626697Y178147I165J112D01*
G01X1627045Y177969D01*
X1627148Y177973D01*
X1627193Y178000D01*
G02X1629000Y178502I1807J-3001D01*
G02Y171498I0J-3502D01*
G02X1627133Y172038I1J3501D01*
G01X1627131D01*
Y172039D01*
G03X1626947Y172053I-105J-170D01*
G01X1626645Y171924D01*
G03X1626569Y171867I78J-184D01*
G01X1626538Y171830D01*
X1626527Y171781D01*
Y171780D01*
G02X1626437Y171437I-3428J716D01*
G03X1626454Y171276I191J-61D01*
G01X1626624Y170982D01*
X1626692Y170933D01*
X1626734Y170924D01*
G02X1629502Y167500I-734J-3424D01*
G02X1628947Y165608I-3502J0D01*
G03Y165392I168J-108D01*
G02X1629502Y163500I-2947J-1892D01*
G02X1622498I-3502J0D01*
G02X1623053Y165392I3502J0D01*
G03Y165608I-168J108D01*
G02X1622498Y167500I2947J1892D01*
G01Y167501D01*
G02X1622663Y168563I3502J0D01*
G03X1622646Y168724I-191J61D01*
G01X1622476Y169018D01*
X1622408Y169067D01*
X1622366Y169076D01*
G02X1619598Y172500I734J3424D01*
G02X1620615Y174967I3501J0D01*
G01X1620616Y174968D01*
X1620644Y174997D01*
X1620659Y175032D01*
G03X1620674Y175109I-185J76D01*
G01Y175371D01*
G03X1620670Y175410I-200J-1D01*
G01X1620659Y175468D01*
X1620644Y175503D01*
X1620616Y175532D01*
X1620615Y175533D01*
G37*
G36*
G01X1646168Y181199D02*
G02X1645000Y180998I-1169J3301D01*
G01X1644998D01*
G02X1643581Y181298I1J3502D01*
G03X1643419I-81J-183D01*
G02X1642002Y180998I-1418J3202D01*
G01X1642000D01*
G02Y188002I0J3502D01*
G01X1642002D01*
G02X1643419Y187702I-1J-3502D01*
G03X1643581I81J183D01*
G02X1644998Y188002I1418J-3202D01*
G01X1645000D01*
G02X1648502Y184500I0J-3502D01*
G02X1648423Y183763I-3502J3D01*
G01X1648417Y183736D01*
X1648420Y183684D01*
X1648429Y183658D01*
G03X1648487Y183570I190J62D01*
G01X1648749Y183340D01*
G03X1648843Y183294I132J150D01*
G03X1648949Y183301I40J196D01*
G02X1650117Y183502I1169J-3301D01*
G02X1653619Y180000I0J-3502D01*
G02X1651680Y176866I-3502J0D01*
G01X1651679D01*
X1651677Y176865D01*
G03X1651603Y176800I91J-178D01*
G03X1651569Y176706I165J-113D01*
G01X1651532Y176316D01*
X1651573Y176221D01*
X1651615Y176190D01*
G02X1653002Y173398I-2117J-2792D01*
G02X1645998I-3502J0D01*
G02X1647937Y176532I3502J0D01*
G01X1647938D01*
X1647940Y176533D01*
G03X1648014Y176598I-91J178D01*
G03X1648048Y176692I-165J113D01*
G01X1648085Y177082D01*
X1648044Y177177D01*
X1648002Y177208D01*
G02X1646615Y180000I2117J2792D01*
G02X1646694Y180737I3502J-3D01*
G01X1646700Y180764D01*
X1646697Y180816D01*
X1646688Y180842D01*
G03X1646630Y180930I-190J-62D01*
G01X1646368Y181160D01*
G03X1646274Y181206I-132J-150D01*
G03X1646168Y181199I-40J-196D01*
G37*
G36*
G01X1658519Y197162D02*
G02X1657998Y199000I2981J1838D01*
G02X1660363Y202312I3502J0D01*
G03X1660498Y202501I-65J189D01*
G02X1664000Y206002I3502J-1D01*
G02X1667502Y202500I0J-3502D01*
G02X1667501Y202402I-3502J-13D01*
G01Y202401D01*
G03X1667552Y202262I200J-6D01*
G01X1667735Y202058D01*
G03X1667869Y201992I149J133D01*
G01X1667870D01*
G02X1671102Y198500I-270J-3492D01*
G02X1667600Y194998I-3502J0D01*
G02X1664685Y196559I0J3502D01*
G03X1664534Y196648I-167J-110D01*
G01X1664223Y196673D01*
G03X1664061Y196611I-17J-199D01*
G01X1664060Y196610D01*
G02X1663135Y195903I-2560J2390D01*
G03X1663035Y195779I93J-177D01*
G01X1662947Y195455D01*
X1662959Y195374D01*
X1662981Y195338D01*
G02X1663502Y193500I-2981J-1838D01*
G02X1660790Y190088I-3502J0D01*
G03X1660655Y189980I45J-195D01*
G02X1657500Y187998I-3155J1520D01*
G02X1655007Y189041I0J3501D01*
G03X1654818Y189095I-142J-141D01*
G02X1654000Y188998I-819J3405D01*
G02Y196002I0J3502D01*
G02X1656493Y194959I0J-3501D01*
G03X1656584Y194906I143J140D01*
G03X1656685I51J194D01*
G02X1656709Y194912I861J-3394D01*
G01X1656711D01*
G03X1656845Y195020I-46J195D01*
G02X1658365Y196597I3155J-1520D01*
G01X1658367D01*
Y196598D01*
G03X1658465Y196721I-95J176D01*
G01X1658553Y197045D01*
X1658541Y197126D01*
X1658519Y197162D01*
G37*
G36*
G01X1780961Y332322D02*
G02X1780440Y330484I-3503J0D01*
G03X1780444Y330268I170J-105D01*
G02X1781034Y328323I-2912J-1945D01*
G01Y328322D01*
G02X1774030I-3502J0D01*
G02X1774551Y330160I3503J0D01*
G03X1774547Y330376I-170J105D01*
G02X1773957Y332321I2912J1945D01*
G01Y332322D01*
G02X1780961I3502J0D01*
G37*
G36*
G01X1766176Y343047D02*
G02X1764198Y346200I1524J3153D01*
G02X1764649Y347918I3502J-1D01*
G03X1764653Y347926I-177J93D01*
G03X1764643Y348124I-179J90D01*
G02X1764098Y350000I2956J1876D01*
G02X1771102I3502J0D01*
G02X1770651Y348282I-3502J1D01*
G03X1770647Y348274I177J-93D01*
G03X1770657Y348076I179J-90D01*
G02X1771202Y346200I-2956J-1876D01*
G02X1770659Y344327I-3502J0D01*
G01X1770636Y344290D01*
X1770624Y344207D01*
X1770730Y343836D01*
X1770784Y343772D01*
X1770824Y343753D01*
G02X1772802Y340600I-1524J-3153D01*
G02X1771730Y338078I-3503J0D01*
G01X1771697Y338047D01*
X1771666Y337965D01*
X1771689Y337616D01*
G03X1771769Y337469I200J13D01*
G01X1771770Y337468D01*
X1771771D01*
G02X1773194Y334649I-2080J-2818D01*
G02X1772023Y332035I-3503J0D01*
G01X1771994Y332009D01*
X1771960Y331941D01*
X1771948Y331780D01*
G03X1771994Y331637I199J-15D01*
G02X1772802Y329400I-2694J-2237D01*
G02X1765798I-3502J0D01*
G01Y329403D01*
G02X1765834Y329904I3502J0D01*
G03X1765718Y330115I-198J29D01*
G02X1763649Y333311I1434J3196D01*
G02X1766849Y336800I3502J0D01*
G03X1766986Y336872I-17J199D01*
G02X1767262Y337171I2707J-2222D01*
G01X1767295Y337202D01*
X1767326Y337284D01*
X1767303Y337633D01*
G03X1767223Y337780I-200J-13D01*
G01X1767222Y337781D01*
X1767221D01*
G02X1765798Y340600I2080J2818D01*
G02X1766341Y342473I3502J0D01*
G01X1766364Y342510D01*
X1766376Y342593D01*
X1766270Y342964D01*
X1766216Y343028D01*
X1766176Y343047D01*
G37*
G36*
G01X1773204Y366313D02*
G03X1773202Y366535I-168J109D01*
G02X1772598Y368500I2898J1966D01*
G01Y368502D01*
G02X1772898Y369919I3502J-1D01*
G03Y370081I-183J81D01*
G02X1772598Y371498I3202J1418D01*
G01Y371500D01*
G02X1779602I3502J0D01*
G01Y371498D01*
G02X1779302Y370081I-3502J1D01*
G03Y369919I183J-81D01*
G02X1779602Y368502I-3202J-1418D01*
G01Y368500D01*
G02X1779036Y366592I-3502J1D01*
G03X1779038Y366370I168J-109D01*
G02X1779642Y364405I-2898J-1966D01*
G02X1779342Y362987I-3501J0D01*
G03X1779340Y362830I183J-81D01*
G02X1779602Y361501I-3240J-1329D01*
G01Y361499D01*
G02X1779147Y359772I-3502J-1D01*
G03X1779126Y359626I173J-99D01*
G01X1779192Y359360D01*
G03X1779223Y359292I194J47D01*
G01X1779245Y359260D01*
X1779278Y359240D01*
G02X1780877Y356300I-1903J-2940D01*
G02X1773873I-3502J0D01*
G01Y356301D01*
G02X1774328Y358028I3502J1D01*
G03X1774349Y358174I-173J99D01*
G01X1774283Y358440D01*
G03X1774252Y358508I-194J-47D01*
G01X1774230Y358540D01*
X1774197Y358560D01*
G02X1772598Y361500I1903J2940D01*
G02X1772898Y362918I3501J0D01*
G03X1772900Y363075I-183J81D01*
G02X1772638Y364403I3240J1329D01*
G01Y364405D01*
G02X1773204Y366313I3502J-1D01*
G37*
G36*
G01X1744327Y369215D02*
G03Y369438I-166J111D01*
G02X1743733Y371389I2907J1951D01*
G01Y371390D01*
G02X1744168Y373080I3502J0D01*
G03Y373273I-175J96D01*
G02X1743733Y374963I3067J1690D01*
G01Y374964D01*
G02X1750737I3502J0D01*
G01Y374963D01*
G02X1750302Y373273I-3502J0D01*
G03Y373080I175J-97D01*
G02X1750737Y371390I-3067J-1690D01*
G01Y371389D01*
G02X1750143Y369438I-3501J0D01*
G03Y369215I166J-112D01*
G02X1750737Y367264I-2907J-1951D01*
G01Y367263D01*
G02X1750302Y365573I-3502J0D01*
G03Y365380I175J-97D01*
G02X1750737Y363690I-3067J-1690D01*
G01Y363689D01*
G02X1750143Y361738I-3501J0D01*
G03Y361515I166J-112D01*
G02X1750737Y359564I-2907J-1951D01*
G01Y359563D01*
G02X1750302Y357873I-3502J0D01*
G03Y357680I175J-97D01*
G02X1750737Y355990I-3067J-1690D01*
G01Y355989D01*
G02X1750210Y354141I-3502J0D01*
G03X1750220Y353916I170J-105D01*
G02X1750918Y351818I-2804J-2098D01*
G01Y351817D01*
G02X1750496Y350150I-3502J0D01*
G03Y349960I176J-95D01*
G02X1750867Y348889I-3080J-1667D01*
G03X1751076Y348723I197J34D01*
G02X1751289Y348729I205J-3496D01*
G02X1754791Y345227I0J-3502D01*
G02X1751462Y341729I-3502J0D01*
G03X1751297Y341628I9J-200D01*
G03X1751279Y341583I175J-96D01*
G02X1751151Y341210I-3371J948D01*
G03Y341059I185J-76D01*
G02Y338411I-3241J-1324D01*
G03Y338259I185J-76D01*
G02Y335611I-3241J-1324D01*
G03Y335459I185J-76D01*
G02X1751411Y334135I-3241J-1324D01*
G02X1747909Y330633I-3502J0D01*
G01X1747907D01*
G02X1746490Y330933I1J3502D01*
G03X1746328I-81J-183D01*
G02X1744910Y330633I-1418J3202D01*
G01X1744908D01*
G02X1743700Y330848I0J3502D01*
G03X1743548Y330843I-70J-188D01*
G02X1742109Y330533I-1440J3192D01*
G02X1738607Y334035I0J3502D01*
G02X1738867Y335359I3501J0D01*
G03Y335511I-185J76D01*
G02Y338159I3241J1324D01*
G03Y338311I-185J76D01*
G02Y340959I3241J1324D01*
G03Y341111I-185J76D01*
G02Y343759I3241J1324D01*
G03Y343911I-185J76D01*
G02X1738607Y345235I3241J1324D01*
G02X1742109Y348737I3502J0D01*
G01X1742111D01*
G02X1743318Y348522I-1J-3502D01*
G03X1743470Y348527I70J188D01*
G02X1743819Y348663I1444J-3190D01*
G03X1743954Y348823I-63J190D01*
G02X1744336Y349960I3462J-530D01*
G03Y350150I-176J95D01*
G02X1743914Y351817I3080J1667D01*
G02X1744441Y353665I3502J0D01*
G03X1744431Y353890I-170J105D01*
G02X1743733Y355988I2804J2098D01*
G01Y355990D01*
G02X1744168Y357680I3502J0D01*
G03Y357873I-175J96D01*
G02X1743733Y359563I3067J1690D01*
G01Y359564D01*
G02X1744327Y361515I3501J0D01*
G03Y361738I-166J111D01*
G02X1743733Y363689I2907J1951D01*
G01Y363690D01*
G02X1744168Y365380I3502J0D01*
G03Y365573I-175J96D01*
G02X1743733Y367263I3067J1690D01*
G01Y367264D01*
G02X1744327Y369215I3501J0D01*
G37*
G36*
G01X1729918Y384204D02*
G03X1729782I-68J-189D01*
G02X1728600Y383998I-1183J3296D01*
G02Y391002I0J3502D01*
G02X1729782Y390796I-1J-3502D01*
G03X1729918I68J189D01*
G02X1731100Y391002I1183J-3296D01*
G02X1732282Y390796I-1J-3502D01*
G03X1732418I68J189D01*
G02X1733600Y391002I1183J-3296D01*
G02Y383998I0J-3502D01*
G02X1732418Y384204I1J3502D01*
G03X1732282I-68J-189D01*
G02X1731100Y383998I-1183J3296D01*
G02X1729918Y384204I1J3502D01*
G37*
G36*
G01Y394204D02*
G03X1729782I-68J-189D01*
G02X1728600Y393998I-1183J3296D01*
G02Y401002I0J3502D01*
G02X1729782Y400796I-1J-3502D01*
G03X1729918I68J189D01*
G02X1731100Y401002I1183J-3296D01*
G02X1732282Y400796I-1J-3502D01*
G03X1732418I68J189D01*
G02X1733600Y401002I1183J-3296D01*
G02Y393998I0J-3502D01*
G02X1732418Y394204I1J3502D01*
G03X1732282I-68J-189D01*
G02X1731100Y393998I-1183J3296D01*
G02X1729918Y394204I1J3502D01*
G37*
G36*
G01X1618101Y145423D02*
X1618100D01*
G02Y152427I0J3502D01*
G02X1621601Y148990I0J-3502D01*
G01X1621602Y148932D01*
X1621634Y148883D01*
G03X1621718Y148811I167J110D01*
G01X1622098Y148637D01*
X1622212Y148653D01*
X1622257Y148690D01*
G02X1624499Y149502I2242J-2690D01*
G01X1624500D01*
G02X1628002Y146000I0J-3502D01*
G02X1627586Y144345I-3502J0D01*
G03Y144155I176J-95D01*
G02X1628002Y142500I-3086J-1655D01*
G02X1620998I-3502J0D01*
G02X1621414Y144155I3502J0D01*
G03Y144345I-176J95D01*
G02X1620999Y145935I3086J1655D01*
G01X1620998Y145993D01*
X1620966Y146042D01*
G03X1620882Y146114I-167J-110D01*
G01X1620502Y146288D01*
X1620388Y146272D01*
X1620343Y146235D01*
G02X1618101Y145423I-2242J2690D01*
G37*
G54D27*
X317000Y74475D03*
X326000Y74476D03*
X330500D03*
X156785Y101285D03*
X321500Y74475D03*
X176785Y102000D03*
X211425Y106075D03*
X317000Y64500D03*
X321500Y66500D03*
X325100Y64000D03*
X332500Y63300D03*
X134600Y134000D03*
X317000Y58000D03*
X187600Y106500D03*
X867100Y28000D03*
X872533Y29432D03*
X862600Y29500D03*
X867100Y31500D03*
X1602100Y62500D03*
X1498180Y63500D03*
X1505100Y64500D03*
X1602100Y66000D03*
X1490228Y66500D03*
X1494728D03*
X1602100Y69500D03*
X1503728Y74477D03*
X1499228Y74500D03*
X1490000Y80500D03*
X1602100Y82000D03*
X1494728Y83500D03*
X1602100Y85500D03*
Y89000D03*
X1706100Y92000D03*
X1721685Y95940D03*
X1531600Y96941D03*
X1527100Y98925D03*
X1727200Y104500D03*
X1767425Y107000D03*
X1719075Y107016D03*
X1614100Y110000D03*
X1719075Y112000D03*
X1767525Y114016D03*
X1701350Y114250D03*
X1759600Y114500D03*
X1594930Y115000D03*
X1614100D03*
X1696600Y119000D03*
X1764100Y119500D03*
X1614100Y120000D03*
X1738000Y124500D03*
X1772975D03*
X1761600Y124524D03*
X1702525Y129500D03*
X1770575Y137000D03*
X1721000Y142525D03*
X1764000D03*
X1773000D03*
X1729411Y143661D03*
X1714100Y144925D03*
X1715525Y153000D03*
X1726099D03*
X1685976Y153500D03*
X1767075Y155484D03*
X1722063Y156962D03*
X1709600Y158000D03*
X1773000D03*
X1764000Y158025D03*
X1685976Y159000D03*
X1701000D03*
X1729411Y159161D03*
X1727100Y164280D03*
X1701000Y164500D03*
X1715525Y168500D03*
X1769476D03*
X1685976Y170000D03*
X1702600Y171500D03*
X1733500Y173760D03*
X1728475Y175000D03*
X1701100Y178500D03*
X1763075Y178900D03*
X1720100Y179500D03*
X1685976Y181000D03*
X1701100Y182000D03*
X1729000Y183500D03*
X1811500Y186000D03*
X1706600Y186500D03*
X1711025Y187000D03*
X1754260Y187260D03*
X1768000D03*
X1800100Y187500D03*
X1778000Y189500D03*
X1738740Y191500D03*
X1721600Y194760D03*
X1809600Y195000D03*
X1750563Y198000D03*
X1721600Y198500D03*
X1747925Y204000D03*
X1789600Y243500D03*
X670184Y288500D03*
X878175Y364709D03*
Y374100D03*
X1017300Y385600D03*
X894500Y396500D03*
X637684Y280575D03*
X712000Y215500D03*
X639010Y236377D03*
X620600Y239161D03*
X645900Y242200D03*
X644502Y246839D03*
X609637Y254523D03*
X604684Y267000D03*
X616184D03*
X686784Y268100D03*
X695584D03*
X674800Y269600D03*
X604684Y276000D03*
X616184D03*
X686784Y278000D03*
X695584D03*
X623684Y281000D03*
X604684Y285000D03*
X616184D03*
X695684Y287900D03*
X616684Y294500D03*
X612684Y297000D03*
X608259Y305000D03*
X616684Y307975D03*
X622184Y308000D03*
X1168200Y349700D03*
X1179500Y350000D03*
X1178900Y359620D03*
X1179500Y355000D03*
X1176000Y350000D03*
X1123400Y356300D03*
X1021414Y355979D03*
X1023492Y346593D03*
X1017300Y322500D03*
X1094500Y355600D03*
X1153500Y342500D03*
X1145600Y244025D03*
X1157138Y303000D03*
X1100500Y263500D03*
X1149600Y255000D03*
X1074430Y256461D03*
X1160990Y252134D03*
X1146100Y285000D03*
Y267000D03*
X1157600D03*
Y276000D03*
X1146100D03*
X1157600Y285000D03*
X1140100Y244000D03*
X1121600Y283000D03*
X1163266Y255311D03*
X1124600Y271425D03*
X1121600Y287500D03*
X1154025Y247000D03*
X1132113Y274500D03*
X1156200Y258900D03*
X1066700Y283900D03*
X1066600Y264100D03*
X1075500Y283900D03*
X1066700Y274000D03*
X1075500D03*
Y264100D03*
X1111100Y285000D03*
X1080600Y294000D03*
X1087100Y282500D03*
X1062600Y305000D03*
X1101600Y289500D03*
X1070525Y243000D03*
X1092100Y263500D03*
X1101500Y271500D03*
X1145600Y257500D03*
X1088079Y274980D03*
X1136000Y278953D03*
X1100100Y247500D03*
X1141600Y312839D03*
X1100100Y243500D03*
X1157800Y312050D03*
X1118000Y303500D03*
X1111100Y300500D03*
Y291500D03*
X1112000Y296000D03*
X1121100D03*
X1102600D03*
X1842164Y419238D03*
Y432338D03*
X1847164Y419238D03*
Y430568D03*
X1837164Y419238D03*
Y428238D03*
X1852164Y419238D03*
Y435538D03*
G54D35*
X1695500Y76500D03*
X1692000Y76570D03*
X1490000Y84000D03*
X1551000Y96500D03*
X1764000Y107000D03*
X1763500Y113000D03*
X1773500Y121000D03*
X1685100Y127500D03*
X1773500Y129500D03*
X1712000Y153000D03*
X1770075Y181500D03*
X1746000Y191240D03*
X662100Y304500D03*
X691759Y309000D03*
X734500Y310575D03*
X663500Y311500D03*
X668000D03*
X719500Y315500D03*
X671000Y315760D03*
X658925Y320000D03*
X710900Y324100D03*
X887500Y355680D03*
X885100Y361500D03*
X880500Y369500D03*
G54D28*
X408100Y180100D03*
Y224500D03*
X1567500Y67000D03*
X632186Y338917D03*
X1173500Y298500D03*
X1355100Y160000D03*
X1355000Y204400D03*
X1652600Y212000D03*
X1631585Y188777D03*
X1762454Y320347D03*
X1777383Y348288D03*
X1672050Y181550D03*
X1679176Y194760D03*
X1668075Y189500D03*
X1635000Y152925D03*
X1636600Y173500D03*
X1658000Y179500D03*
X1658500Y138000D03*
X1667000D03*
X1638707Y132954D03*
X1649197Y132915D03*
G54D30*
X166785Y230000D03*
X243785D03*
X166785Y310000D03*
X243785D03*
X166785Y390000D03*
X243785D03*
X166785Y470000D03*
X243785D03*
X166785Y550000D03*
X243785D03*
X1488500Y230000D03*
X1565500D03*
X1488500Y310000D03*
X1565500D03*
X1488500Y390000D03*
X1565500D03*
X1488500Y470000D03*
X1565500D03*
X1488500Y550000D03*
X1565500D03*
G54D37*
X623500Y379000D03*
G54D36*
X866400Y362200D03*
X906901D03*
X866400Y372200D03*
X906901D03*
X825900Y382200D03*
X866400D03*
G54D34*
X274646Y18012D03*
X284646D03*
X1465197D03*
X1475197D03*
X250866Y20827D03*
X260866D03*
X1441417D03*
X1451417D03*
X279646Y23012D03*
X289646D03*
X1470197D03*
X1480197D03*
G54D33*
X260866Y10197D03*
X1451417D03*
G54D29*
X166785Y200472D03*
X243785D03*
X166785Y280472D03*
X243785D03*
X166785Y360472D03*
X243785D03*
X166785Y440472D03*
X243785D03*
X166785Y520472D03*
X243785D03*
X1488500Y200472D03*
X1565500D03*
X1488500Y280472D03*
X1565500D03*
X1488500Y360472D03*
X1565500D03*
X1488500Y440472D03*
X1565500D03*
X1488500Y520472D03*
X1565500D03*
G54D38*
X1851457Y220433D03*
G54D32*
X287402Y628465D03*
X1468504D03*
X1444882Y659961D03*
G54D31*
X393703Y354332D03*
X1452757Y62992D03*
X984253Y354330D03*
X1685041Y340552D03*
G54D26*
X231600Y81000D03*
X1529100Y78500D03*
X1212478Y300181D03*
G54D39*
X1673228Y236614D03*
G54D25*
X59055Y411594D03*
Y236614D03*
X1673228Y411614D03*
%LPD*%
G75*
G54D10*
X3018Y23930D03*
X10493Y5830D03*
X3018Y43930D03*
Y83930D03*
Y63930D03*
Y103930D03*
Y143930D03*
Y123930D03*
Y163930D03*
Y203930D03*
Y183930D03*
Y223930D03*
Y263930D03*
Y243930D03*
Y283930D03*
Y323930D03*
Y303930D03*
Y343930D03*
Y383930D03*
Y363930D03*
Y403930D03*
Y443930D03*
Y423930D03*
Y463930D03*
Y503930D03*
Y483930D03*
Y523930D03*
Y563930D03*
Y543930D03*
Y583930D03*
X15642Y619715D03*
X3018Y603930D03*
X30709Y3014D03*
X35455Y620194D03*
X75455D03*
X55455D03*
X81406Y3042D03*
X101406D03*
X95455Y620194D03*
X121406Y3042D03*
X137355Y120500D03*
X114923Y623982D03*
X124901Y640105D03*
X161406Y3042D03*
X141406D03*
X154778Y672779D03*
X181406Y3042D03*
X194778Y672779D03*
X174778D03*
X201406Y3042D03*
X221406D03*
X205061Y85500D03*
Y79000D03*
Y75000D03*
Y71500D03*
Y67500D03*
Y89500D03*
Y93000D03*
Y97000D03*
X200600Y109059D03*
X225829Y103412D03*
Y99503D03*
X225953Y95780D03*
X225891Y92305D03*
X214778Y672779D03*
X229829Y99503D03*
X233329D03*
X237329D03*
X229953Y95780D03*
X233453D03*
X237453D03*
X229891Y92305D03*
X233391D03*
X237391D03*
X254778Y672779D03*
X234778D03*
X274778D03*
X314766Y39211D03*
X317766D03*
X311956Y651522D03*
X294778Y672779D03*
X323766Y39211D03*
X320766D03*
X324000Y77000D03*
X321000Y63000D03*
X345412Y435017D03*
Y455017D03*
Y475017D03*
Y495017D03*
Y515017D03*
Y535017D03*
Y555017D03*
Y575017D03*
Y595017D03*
X342119Y613510D03*
X331285Y620008D03*
X369192Y38417D03*
X372192D03*
X378192D03*
X375192D03*
X362127Y406608D03*
X350024Y418335D03*
X399680Y402510D03*
X379680D03*
X438100Y170000D03*
Y214500D03*
X419680Y402510D03*
X454738Y56000D03*
X451738D03*
X448738D03*
X445738D03*
X442738D03*
X454738Y68000D03*
Y65000D03*
Y62000D03*
Y59000D03*
X451738D03*
Y62000D03*
Y65000D03*
Y68000D03*
X448738Y59000D03*
Y62000D03*
Y65000D03*
Y68000D03*
X445738Y59000D03*
Y62000D03*
Y65000D03*
Y68000D03*
X442738Y59000D03*
Y62000D03*
Y65000D03*
Y68000D03*
X454738Y112400D03*
Y109400D03*
Y106400D03*
Y103400D03*
X451738D03*
Y106400D03*
Y109400D03*
Y112400D03*
X448738Y103400D03*
Y106400D03*
Y109400D03*
Y112400D03*
X445738Y103400D03*
Y106400D03*
Y109400D03*
Y112400D03*
X442738Y103400D03*
Y106400D03*
Y109400D03*
Y112400D03*
X454738Y100400D03*
X451738D03*
X448738D03*
X445738D03*
X442738D03*
X454738Y147800D03*
X451738D03*
X448738D03*
X445738D03*
X442738D03*
X454738Y144800D03*
X451738D03*
X448738D03*
X445738D03*
X442738D03*
X454738Y156800D03*
Y153800D03*
Y150800D03*
X451738D03*
Y153800D03*
Y156800D03*
X448738Y150800D03*
Y153800D03*
Y156800D03*
X445738Y150800D03*
Y153800D03*
Y156800D03*
X442738Y150800D03*
Y153800D03*
Y156800D03*
X454738Y201200D03*
Y198200D03*
Y195200D03*
Y192200D03*
X451738D03*
Y195200D03*
Y198200D03*
Y201200D03*
X448738Y192200D03*
Y195200D03*
Y198200D03*
Y201200D03*
X445738Y192200D03*
Y195200D03*
Y198200D03*
Y201200D03*
X442738Y192200D03*
Y195200D03*
Y198200D03*
Y201200D03*
X454738Y189200D03*
X451738D03*
X448738D03*
X445738D03*
X442738D03*
X454738Y239600D03*
Y236600D03*
X451738D03*
Y239600D03*
X448738Y236600D03*
Y239600D03*
X445738Y236600D03*
Y239600D03*
X442738Y236600D03*
Y239600D03*
X454738Y233600D03*
X451738D03*
X448738D03*
X445738D03*
X442738D03*
X454738Y245600D03*
Y242600D03*
X451738D03*
Y245600D03*
X448738Y242600D03*
Y245600D03*
X445738Y242600D03*
Y245600D03*
X442738Y242600D03*
Y245600D03*
X448738Y278000D03*
X451738D03*
X454738D03*
X448738Y290000D03*
Y287000D03*
Y284000D03*
Y281000D03*
X451738Y290000D03*
Y287000D03*
Y284000D03*
Y281000D03*
X454738D03*
Y284000D03*
Y287000D03*
Y290000D03*
X445738D03*
Y287000D03*
Y284000D03*
Y281000D03*
Y278000D03*
X442738Y290000D03*
Y287000D03*
Y284000D03*
Y281000D03*
Y278000D03*
X468946Y338216D03*
X465946D03*
X468946Y341216D03*
X465946D03*
X458946Y338216D03*
X455946D03*
X458946Y341216D03*
X455946D03*
X459680Y402510D03*
X439680D03*
X498923Y37456D03*
X495923D03*
X492923D03*
X489923D03*
X471946Y338216D03*
Y341216D03*
X481446Y338216D03*
X478446D03*
X481446Y341216D03*
X478446D03*
X484446Y338216D03*
Y341216D03*
X479680Y402510D03*
X501923Y37456D03*
X504923D03*
X510923D03*
X507923D03*
X528084Y77900D03*
Y74900D03*
Y71900D03*
Y68900D03*
Y65900D03*
X525084Y77900D03*
Y74900D03*
Y71900D03*
Y68900D03*
Y65900D03*
X522084Y77900D03*
Y74900D03*
Y71900D03*
Y68900D03*
Y65900D03*
X525084Y116300D03*
Y113300D03*
Y110300D03*
X522084Y113300D03*
Y116300D03*
Y110300D03*
X528084Y116300D03*
Y113300D03*
Y110300D03*
X525084Y122300D03*
X522084D03*
X525084Y119300D03*
X522084D03*
X528084Y122300D03*
Y119300D03*
X525084Y166700D03*
X522084D03*
X525084Y160700D03*
Y163700D03*
Y157700D03*
Y154700D03*
X522084Y157700D03*
Y163700D03*
Y160700D03*
Y154700D03*
Y199100D03*
Y205100D03*
Y208100D03*
Y202100D03*
X525084Y199100D03*
Y202100D03*
Y208100D03*
Y205100D03*
X522084Y211100D03*
X525084D03*
X522084Y243500D03*
Y249500D03*
Y252500D03*
Y246500D03*
X525084Y243500D03*
Y246500D03*
Y252500D03*
Y249500D03*
X522084Y255500D03*
X525084D03*
X528084Y243500D03*
Y246500D03*
Y252500D03*
Y249500D03*
Y255500D03*
Y299900D03*
X525084D03*
X522084D03*
X528084Y296900D03*
X525084D03*
X522084D03*
X528084Y293900D03*
X525084D03*
X522084D03*
X528084Y290900D03*
Y287900D03*
X525084D03*
Y290900D03*
X522084D03*
Y287900D03*
X499680Y402510D03*
X519680D03*
X531084Y77900D03*
Y74900D03*
Y71900D03*
Y68900D03*
Y65900D03*
Y299900D03*
Y296900D03*
Y293900D03*
Y290900D03*
Y287900D03*
X539680Y402510D03*
X559680D03*
X586184Y117800D03*
X583184D03*
X580184D03*
X586184Y114800D03*
X583184D03*
X580184D03*
X586184Y111800D03*
X583184D03*
X580184D03*
X586184Y108800D03*
X583184D03*
X580184D03*
X586184Y105800D03*
X583184D03*
X580184D03*
Y126800D03*
X583184D03*
X586184D03*
Y123800D03*
X583184D03*
X580184D03*
X586184Y120800D03*
X583184D03*
X580184D03*
X583184Y239000D03*
X580184D03*
X583184Y242000D03*
X580184D03*
X583184Y254000D03*
Y251000D03*
Y248000D03*
Y245000D03*
X580184D03*
Y248000D03*
Y251000D03*
Y254000D03*
X583184Y260000D03*
Y257000D03*
X580184D03*
Y260000D03*
X579680Y402510D03*
X620466Y246839D03*
X601675Y305575D03*
X619680Y402510D03*
X599680D03*
X645784Y43500D03*
X648784D03*
X645784Y40500D03*
X648784D03*
X645784Y99000D03*
X648784D03*
X645784Y96000D03*
X648784D03*
X622288Y235790D03*
X624788D03*
X649059Y314000D03*
X639680Y402510D03*
X651784Y43500D03*
Y40500D03*
X657784D03*
X654784D03*
X657784Y43500D03*
X654784D03*
X651784Y99000D03*
Y96000D03*
X657784D03*
X654784D03*
X657784Y99000D03*
X654784D03*
X664484Y212500D03*
X666984D03*
X672484D03*
X674984D03*
X679484D03*
X662184Y288500D03*
Y284500D03*
X657500Y330075D03*
X662075Y320000D03*
X675100Y304500D03*
X662125Y308500D03*
X659680Y402510D03*
X679680D03*
X704200Y206569D03*
X681984Y212500D03*
X685484D03*
X687984D03*
X699680Y402510D03*
X736554Y131056D03*
Y128056D03*
X739554Y131056D03*
Y128056D03*
X742554D03*
X732100Y185000D03*
X729100D03*
X726100D03*
X720100D03*
X723100D03*
X726100Y188000D03*
X729100D03*
X732100D03*
X723100D03*
X720100D03*
X726000Y231500D03*
X729000D03*
X723000D03*
X720000D03*
X732000D03*
Y228500D03*
X720000D03*
X723000D03*
X726000D03*
X729000D03*
X717384Y273400D03*
X734500Y307425D03*
X739680Y402510D03*
X719680D03*
X742554Y131056D03*
X749600Y185000D03*
X752600D03*
X755600D03*
X758600D03*
X746600Y188000D03*
X758600D03*
X755600D03*
X752600D03*
X749600D03*
X746600Y185000D03*
X758500Y231500D03*
X746500D03*
X755500D03*
X752500D03*
X749500D03*
X746500Y228500D03*
X755500D03*
X752500D03*
X749500D03*
X758500D03*
X759680Y402510D03*
X779680D03*
X799680D03*
X819680D03*
X839680D03*
X859680D03*
X879680D03*
X919680D03*
X899680D03*
X939680D03*
X983500Y185000D03*
Y188000D03*
X980500Y185000D03*
X974500D03*
X977500D03*
X980500Y188000D03*
X977500D03*
X974500D03*
Y231500D03*
X977500D03*
X983500D03*
X980500D03*
X983500Y228500D03*
X980500D03*
X977500D03*
X974500D03*
X978600Y310955D03*
X959680Y402510D03*
X979680D03*
X990954Y131056D03*
Y128056D03*
X993954Y131056D03*
Y128056D03*
X996954D03*
Y131056D03*
X986500Y185000D03*
Y188000D03*
X1004000Y185000D03*
X1001000Y188000D03*
X1004000D03*
X1007000Y185000D03*
X1010000D03*
X1013000D03*
Y188000D03*
X1010000D03*
X1007000D03*
X1001000Y185000D03*
X1004000Y231500D03*
X1007000D03*
X1010000D03*
X1001000D03*
X986500D03*
X1013000D03*
X986500Y228500D03*
X1013000D03*
X1004000D03*
X1007000D03*
X1010000D03*
X1001000D03*
X999680Y402510D03*
X1044900Y278600D03*
X1039680Y402510D03*
X1019680D03*
X1059680D03*
X1101500Y268500D03*
X1079680Y402510D03*
X1099680D03*
X1118500Y283000D03*
X1119680Y402510D03*
X1143500Y251500D03*
X1141600Y305161D03*
X1154600Y321050D03*
X1143100Y322500D03*
Y320000D03*
X1147000Y342500D03*
X1159680Y402510D03*
X1139680D03*
X1176100Y105800D03*
Y108800D03*
X1182100Y105800D03*
Y108800D03*
X1179100D03*
Y105800D03*
X1176100Y111800D03*
Y114800D03*
Y117800D03*
X1182100Y111800D03*
Y114800D03*
Y117800D03*
X1179100D03*
Y114800D03*
Y111800D03*
X1176100Y126800D03*
Y123800D03*
Y120800D03*
X1182100Y126800D03*
Y123800D03*
Y120800D03*
X1179100D03*
Y123800D03*
Y126800D03*
X1176100Y239000D03*
X1171600Y238000D03*
X1179100Y239000D03*
X1182100D03*
X1176100Y254000D03*
Y251000D03*
Y248000D03*
Y245000D03*
Y257000D03*
Y260000D03*
Y242000D03*
X1171600Y241500D03*
X1179100Y242000D03*
Y260000D03*
Y257000D03*
Y245000D03*
Y248000D03*
Y251000D03*
Y254000D03*
X1182100D03*
Y251000D03*
Y248000D03*
Y245000D03*
Y257000D03*
Y260000D03*
Y242000D03*
X1167800Y355000D03*
X1165575Y340500D03*
X1171700Y349900D03*
X1178500Y368740D03*
X1179680Y402510D03*
X1225930Y359148D03*
X1199680Y402510D03*
X1219680D03*
X1240200Y77900D03*
Y74900D03*
Y71900D03*
Y68900D03*
Y65900D03*
X1237200D03*
Y68900D03*
Y71900D03*
Y74900D03*
Y77900D03*
X1234200Y65900D03*
Y68900D03*
Y71900D03*
Y74900D03*
Y77900D03*
X1231200Y65900D03*
Y68900D03*
Y71900D03*
Y74900D03*
Y77900D03*
X1234200Y116300D03*
Y113300D03*
Y110300D03*
X1237200Y116300D03*
Y113300D03*
Y110300D03*
X1240200D03*
Y113300D03*
Y116300D03*
X1234200Y122300D03*
Y119300D03*
X1237200Y122300D03*
Y119300D03*
X1240200D03*
Y122300D03*
X1237200Y166700D03*
Y163700D03*
Y160700D03*
Y157700D03*
Y154700D03*
X1240200D03*
Y157700D03*
Y160700D03*
Y163700D03*
Y166700D03*
X1237200Y205100D03*
Y202100D03*
Y199100D03*
Y208100D03*
X1240200D03*
Y199100D03*
Y202100D03*
Y205100D03*
X1237200Y211100D03*
X1240200D03*
X1234200Y249500D03*
Y246500D03*
Y243500D03*
Y252500D03*
X1237200Y249500D03*
Y246500D03*
Y243500D03*
Y252500D03*
X1234200Y255500D03*
X1237200D03*
X1240200Y252500D03*
Y243500D03*
Y246500D03*
Y249500D03*
Y255500D03*
Y293900D03*
Y290900D03*
Y287900D03*
Y299900D03*
Y296900D03*
X1237200D03*
Y287900D03*
Y290900D03*
Y293900D03*
Y299900D03*
X1234200Y296900D03*
Y287900D03*
Y290900D03*
Y293900D03*
Y299900D03*
X1231200Y293900D03*
Y290900D03*
Y287900D03*
Y296900D03*
Y299900D03*
X1242930Y359148D03*
Y356148D03*
X1245930Y359148D03*
Y356148D03*
X1248930Y359148D03*
Y356148D03*
X1231930D03*
Y359148D03*
X1228930Y356148D03*
Y359148D03*
X1225930Y356148D03*
X1253930Y379648D03*
X1250930D03*
X1247930D03*
X1239680Y402510D03*
X1260340Y359284D03*
Y356284D03*
X1263340Y359284D03*
Y356284D03*
X1266340Y359284D03*
Y356284D03*
X1286113Y378312D03*
X1265340Y379784D03*
X1268340D03*
X1271340D03*
X1259680Y402510D03*
X1279680D03*
X1307700Y78900D03*
Y81900D03*
X1310700D03*
Y78900D03*
X1313700Y81900D03*
Y78900D03*
X1307700Y84900D03*
Y87900D03*
X1310700D03*
Y84900D03*
X1313700Y87900D03*
Y84900D03*
X1307700Y90900D03*
X1310700D03*
X1313700D03*
X1307700Y123300D03*
Y126300D03*
X1310700D03*
Y123300D03*
X1313700Y126300D03*
Y123300D03*
X1307700Y129300D03*
Y132300D03*
Y135300D03*
X1310700D03*
Y132300D03*
Y129300D03*
X1313700Y135300D03*
Y132300D03*
Y129300D03*
Y167700D03*
Y170700D03*
Y173700D03*
Y176700D03*
X1310700Y167700D03*
Y170700D03*
Y173700D03*
Y176700D03*
X1307700D03*
Y173700D03*
Y170700D03*
Y167700D03*
X1313700Y179700D03*
X1310700D03*
X1307700D03*
Y212100D03*
Y215100D03*
X1310700D03*
Y212100D03*
X1313700Y215100D03*
Y212100D03*
X1307700Y218100D03*
Y221100D03*
Y224100D03*
X1310700D03*
Y221100D03*
Y218100D03*
X1313700Y224100D03*
Y221100D03*
Y218100D03*
X1307700Y256500D03*
Y259500D03*
X1310700D03*
Y256500D03*
X1313700Y259500D03*
Y256500D03*
X1307700Y262500D03*
Y265500D03*
Y268500D03*
X1310700D03*
Y265500D03*
Y262500D03*
X1313700Y268500D03*
Y265500D03*
Y262500D03*
X1307700Y300900D03*
Y303900D03*
X1310700D03*
Y300900D03*
X1313700Y303900D03*
Y300900D03*
X1307700Y306900D03*
Y309900D03*
Y312900D03*
X1310700D03*
Y309900D03*
Y306900D03*
X1313700Y309900D03*
Y306900D03*
X1286113Y375312D03*
X1289113Y378312D03*
Y375312D03*
X1292113Y378312D03*
Y375312D03*
Y372312D03*
X1289113D03*
X1299680Y402510D03*
X1316700Y81900D03*
Y78900D03*
X1319700Y81900D03*
Y78900D03*
X1316700Y87900D03*
Y84900D03*
X1319700Y87900D03*
Y84900D03*
X1316700Y90900D03*
X1319700D03*
X1316700Y126300D03*
Y123300D03*
X1319700Y126300D03*
Y123300D03*
X1316700Y135300D03*
Y132300D03*
Y129300D03*
X1319700Y135300D03*
Y132300D03*
Y129300D03*
Y167700D03*
Y170700D03*
Y173700D03*
Y176700D03*
X1316700Y167700D03*
Y170700D03*
Y173700D03*
Y176700D03*
X1324100Y150500D03*
Y194900D03*
X1316700Y215100D03*
Y212100D03*
X1319700Y215100D03*
Y212100D03*
X1316700Y224100D03*
Y221100D03*
Y218100D03*
X1319700Y224100D03*
Y221100D03*
Y218100D03*
X1316700Y259500D03*
Y256500D03*
X1319700Y259500D03*
Y256500D03*
X1316700Y268500D03*
Y265500D03*
Y262500D03*
X1319700Y268500D03*
Y265500D03*
Y262500D03*
X1316700Y303900D03*
Y300900D03*
X1319700Y303900D03*
Y300900D03*
X1316700Y306900D03*
X1339680Y402510D03*
X1319680D03*
X1359620Y402940D03*
X1386882Y434539D03*
Y454539D03*
Y474539D03*
Y494539D03*
Y514539D03*
Y534539D03*
Y554539D03*
Y574539D03*
Y594539D03*
X1389643Y612723D03*
X1403035Y620181D03*
X1420335Y635388D03*
Y655388D03*
X1428754Y670547D03*
X1445829Y672778D03*
X1465829D03*
X1485829D03*
X1508460Y3003D03*
X1505829Y672778D03*
X1525829D03*
X1548460Y3003D03*
X1528460D03*
X1545829Y672778D03*
X1588460Y3003D03*
X1568460D03*
X1565829Y672778D03*
X1585829D03*
X1608460Y3003D03*
X1614100Y125000D03*
X1613527Y627220D03*
X1607226Y650448D03*
X1602599Y667628D03*
X1648460Y3003D03*
X1628460D03*
X1622295Y114940D03*
X1625370Y103940D03*
X1622295Y118940D03*
X1628658Y620261D03*
X1648675Y620226D03*
X1660250Y113860D03*
X1657050Y116760D03*
Y113860D03*
X1660250Y116760D03*
X1669800Y120400D03*
X1675800D03*
X1672800D03*
X1668675Y620226D03*
X1708460Y3003D03*
X1682500Y121825D03*
X1697976Y148000D03*
X1690100Y127375D03*
X1697976Y164500D03*
Y159000D03*
Y175500D03*
Y170000D03*
Y153500D03*
X1680000Y156500D03*
X1697975Y181000D03*
X1704600Y201500D03*
X1688692Y620191D03*
X1708692D03*
X1729255Y25347D03*
Y45347D03*
X1718675Y88000D03*
X1732786Y58461D03*
X1718675Y99000D03*
Y93500D03*
X1713524Y109500D03*
Y114500D03*
X1713525Y134500D03*
Y129500D03*
X1713524Y119500D03*
X1720524Y175000D03*
X1717600Y158000D03*
X1731925Y199000D03*
X1714175Y187000D03*
X1729275Y562751D03*
Y542751D03*
Y582751D03*
Y602751D03*
X1753635Y69037D03*
X1767425Y137000D03*
X1768500Y142525D03*
X1759925Y178900D03*
X1768500Y158025D03*
X1763925Y170984D03*
Y155484D03*
X1766925Y181500D03*
X1769425Y203000D03*
X1754925D03*
X1751600Y258000D03*
Y255500D03*
X1740600Y258000D03*
Y255500D03*
Y248000D03*
Y250500D03*
Y253000D03*
X1751600D03*
Y250500D03*
Y248000D03*
X1766432Y250301D03*
Y247301D03*
X1755454Y515746D03*
X1793635Y69037D03*
X1773635D03*
X1772975Y109500D03*
Y104500D03*
X1773076Y117500D03*
X1789600Y247000D03*
X1783932Y250357D03*
Y247357D03*
X1775432Y250357D03*
Y247357D03*
X1795600Y308000D03*
X1777383Y352305D03*
X1784035Y389535D03*
X1781535D03*
X1784035Y386935D03*
X1781535D03*
X1778838Y389508D03*
Y386908D03*
X1781535Y402935D03*
X1784035D03*
X1778838Y402908D03*
X1781535Y405535D03*
X1784035D03*
X1778838Y405508D03*
X1775454Y515746D03*
X1813635Y69037D03*
X1815454Y515746D03*
X1853635Y69037D03*
X1833635D03*
X1844500Y416500D03*
X1847500Y437000D03*
X1835454Y515746D03*
X1855509Y515697D03*
X1871008Y117112D03*
X1871009Y93913D03*
X1871008Y137112D03*
Y177112D03*
Y157112D03*
Y197112D03*
Y237112D03*
Y217112D03*
Y257112D03*
Y297112D03*
Y277112D03*
Y317112D03*
Y357112D03*
Y337112D03*
Y377112D03*
Y417112D03*
Y397112D03*
Y437112D03*
Y477112D03*
Y457112D03*
Y497112D03*
G54D11*
X32284Y541339D03*
X59055Y498032D03*
X1673228D03*
X1700000Y541339D03*
G54D20*
X1835739Y99212D03*
X1835738Y481693D03*
G54D21*
X1846142Y230433D03*
Y240433D03*
X1856772D03*
Y230433D03*
X1846142Y250433D03*
Y260433D03*
X1856772D03*
Y250433D03*
X1843957Y329213D03*
X1848957Y314213D03*
X1858957Y324213D03*
Y314213D03*
X1848957Y344213D03*
X1843957Y349213D03*
G36*
G01X37224Y31090D02*
G02X57265Y31089I10021J6311D01*
G03X55150Y23763I11632J-7326D01*
G01Y17716D01*
G02X39338I-7906J0D01*
G01Y23763D01*
G03X37224Y31090I-13749J2D01*
G37*
G36*
G01Y344082D02*
G02X57265Y344081I10021J6311D01*
G03X55150Y336755I11632J-7326D01*
G01Y330708D01*
G02X39338I-7906J0D01*
G01Y336755D01*
G03X37224Y344082I-13749J2D01*
G37*
G36*
G01X269508Y66522D02*
G02X289549Y66521I10021J6311D01*
G03X287434Y59195I11632J-7326D01*
G01Y53148D01*
G02X271622I-7906J0D01*
G01Y59195D01*
G03X269508Y66522I-13749J2D01*
G37*
G36*
G01X738012Y78335D02*
G02X758053Y78334I10021J6311D01*
G03X755938Y71008I11632J-7326D01*
G01Y64961D01*
G02X740126I-7906J0D01*
G01Y71008D01*
G03X738012Y78335I-13749J2D01*
G37*
G36*
G01Y357862D02*
G02X758053Y357861I10021J6311D01*
G03X755938Y350535I11632J-7326D01*
G01Y344488D01*
G02X740126I-7906J0D01*
G01Y350535D01*
G03X738012Y357862I-13749J2D01*
G37*
G36*
G01X1328564D02*
G02X1348605Y357861I10021J6311D01*
G03X1346490Y350535I11632J-7326D01*
G01Y344488D01*
G02X1330678I-7906J0D01*
G01Y350535D01*
G03X1328564Y357862I-13749J2D01*
G37*
G36*
G01X1789192Y491720D02*
G02X1809233Y491719I10021J6311D01*
G03X1807118Y484393I11632J-7326D01*
G01Y478346D01*
G02X1791306I-7906J0D01*
G01Y484393D01*
G03X1789192Y491720I-13749J2D01*
G37*
G54D22*
G01X163614Y226829D02*
X166785Y230000D01*
G01D02*
X169956Y233171D01*
G01X163614D02*
X166785Y230000D01*
G01D02*
X169956Y226829D01*
G01X163614Y306829D02*
X166785Y310000D01*
G01D02*
X169956Y313171D01*
G01X163614D02*
X166785Y310000D01*
G01D02*
X169956Y306829D01*
G01X163614Y386829D02*
X166785Y390000D01*
G01D02*
X169956Y393171D01*
G01X163614D02*
X166785Y390000D01*
G01D02*
X169956Y386829D01*
G01X163614Y466829D02*
X166785Y470000D01*
G01D02*
X169956Y473171D01*
G01X163614D02*
X166785Y470000D01*
G01D02*
X169956Y466829D01*
G01X163614Y546829D02*
X166785Y550000D01*
G01D02*
X169956Y553171D01*
G01X163614D02*
X166785Y550000D01*
G01D02*
X169956Y546829D01*
G01X240614Y226829D02*
X243785Y230000D01*
G01D02*
X246956Y233171D01*
G01X240614D02*
X243785Y230000D01*
G01D02*
X246956Y226829D01*
G01X240614Y306829D02*
X243785Y310000D01*
G01D02*
X246956Y313171D01*
G01X240614D02*
X243785Y310000D01*
G01D02*
X246956Y306829D01*
G01X240614Y386829D02*
X243785Y390000D01*
G01D02*
X246956Y393171D01*
G01X240614D02*
X243785Y390000D01*
G01D02*
X246956Y386829D01*
G01X240614Y466829D02*
X243785Y470000D01*
G01D02*
X246956Y473171D01*
G01X240614D02*
X243785Y470000D01*
G01D02*
X246956Y466829D01*
G01X240614Y546829D02*
X243785Y550000D01*
G01D02*
X246956Y553171D01*
G01X240614D02*
X243785Y550000D01*
G01D02*
X246956Y546829D01*
G01X1485329Y226829D02*
X1488500Y230000D01*
G01D02*
X1491671Y233171D01*
G01X1485329D02*
X1488500Y230000D01*
G01D02*
X1491671Y226829D01*
G01X1485329Y306829D02*
X1488500Y310000D01*
G01D02*
X1491671Y313171D01*
G01X1485329D02*
X1488500Y310000D01*
G01D02*
X1491671Y306829D01*
G01X1485329Y386829D02*
X1488500Y390000D01*
G01D02*
X1491671Y393171D01*
G01X1485329D02*
X1488500Y390000D01*
G01D02*
X1491671Y386829D01*
G01X1485329Y466829D02*
X1488500Y470000D01*
G01D02*
X1491671Y473171D01*
G01X1485329D02*
X1488500Y470000D01*
G01D02*
X1491671Y466829D01*
G01X1485329Y546829D02*
X1488500Y550000D01*
G01D02*
X1491671Y553171D01*
G01X1485329D02*
X1488500Y550000D01*
G01D02*
X1491671Y546829D01*
G01X1562329Y226829D02*
X1565500Y230000D01*
G01D02*
X1568671Y233171D01*
G01X1562329D02*
X1565500Y230000D01*
G01D02*
X1568671Y226829D01*
G01X1562329Y306829D02*
X1565500Y310000D01*
G01D02*
X1568671Y313171D01*
G01X1562329D02*
X1565500Y310000D01*
G01D02*
X1568671Y306829D01*
G01X1562329Y386829D02*
X1565500Y390000D01*
G01D02*
X1568671Y393171D01*
G01X1562329D02*
X1565500Y390000D01*
G01D02*
X1568671Y386829D01*
G01X1562329Y466829D02*
X1565500Y470000D01*
G01D02*
X1568671Y473171D01*
G01X1562329D02*
X1565500Y470000D01*
G01D02*
X1568671Y466829D01*
G01X1562329Y546829D02*
X1565500Y550000D01*
G01D02*
X1568671Y553171D01*
G01X1562329D02*
X1565500Y550000D01*
G01D02*
X1568671Y546829D01*
G54D13*
X45275Y236614D03*
Y411594D03*
X72835Y236614D03*
X68898Y226771D03*
X59055Y222834D03*
X49212Y226771D03*
X68898Y246457D03*
X49212D03*
X59055Y250394D03*
X68898Y421437D03*
X72835Y411594D03*
X68898Y401751D03*
X59055Y397814D03*
X49212Y401751D03*
Y421437D03*
X59055Y425374D03*
X1673228Y397834D03*
X1663385Y401771D03*
X1659448Y411614D03*
X1663385Y421457D03*
X1673228Y425394D03*
X1683071Y421457D03*
X1687008Y411614D03*
X1683071Y401771D03*
G54D23*
G01X-457143Y-1211429D02*
Y2242857D01*
X4308572D01*
Y-1211429D01*
X-457143D01*
G01X37000Y-995000D02*
Y-1070000D01*
X537000D01*
Y-995000D01*
X37000D01*
G01X49000Y-1060000D02*
Y-1065000D01*
G01X47543Y-1060000D02*
X50457D01*
G01X55367Y-1065000D02*
X52833D01*
Y-1060000D01*
X55367D01*
G01X54353Y-1062417D02*
X52833D01*
G01X57933Y-1060000D02*
Y-1065000D01*
X60467D01*
G01X64300Y-1065167D02*
X64173Y-1065083D01*
Y-1064917D01*
X64300Y-1064833D01*
X64427Y-1064917D01*
Y-1065083D01*
X64300Y-1065167D01*
G01Y-1062917D02*
X64173Y-1062833D01*
Y-1062667D01*
X64300Y-1062583D01*
X64427Y-1062667D01*
Y-1062833D01*
X64300Y-1062917D01*
G01X69083Y-1066667D02*
X68450Y-1065833D01*
X68133Y-1065000D01*
Y-1061667D01*
X68450Y-1060833D01*
X69083Y-1060000D01*
G01X74500D02*
X73993Y-1060167D01*
X73613Y-1060583D01*
X73360Y-1061083D01*
X73170Y-1061750D01*
X73107Y-1062500D01*
X73170Y-1063250D01*
X73360Y-1063917D01*
X73613Y-1064417D01*
X73993Y-1064833D01*
X74500Y-1065000D01*
X75007Y-1064833D01*
X75387Y-1064417D01*
X75640Y-1063917D01*
X75830Y-1063250D01*
X75893Y-1062500D01*
X75830Y-1061750D01*
X75640Y-1061083D01*
X75387Y-1060583D01*
X75007Y-1060167D01*
X74500Y-1060000D01*
G01X78207Y-1064000D02*
X78587Y-1064583D01*
X79093Y-1064917D01*
X79663Y-1065000D01*
X80170Y-1064917D01*
X80677Y-1064500D01*
X80993Y-1064000D01*
X81057Y-1063500D01*
X80930Y-1062917D01*
X80487Y-1062500D01*
X80043Y-1062333D01*
X79473D01*
G01X80043D02*
X80423Y-1062083D01*
X80740Y-1061667D01*
X80867Y-1061167D01*
X80740Y-1060667D01*
X80423Y-1060250D01*
X79853Y-1060000D01*
X79283Y-1060083D01*
X78713Y-1060417D01*
G01X85017Y-1066667D02*
X85650Y-1065833D01*
X85967Y-1065000D01*
Y-1061667D01*
X85650Y-1060833D01*
X85017Y-1060000D01*
G01X88407Y-1064000D02*
X88787Y-1064583D01*
X89293Y-1064917D01*
X89863Y-1065000D01*
X90370Y-1064917D01*
X90877Y-1064500D01*
X91193Y-1064000D01*
X91257Y-1063500D01*
X91130Y-1062917D01*
X90687Y-1062500D01*
X90243Y-1062333D01*
X89673D01*
G01X90243D02*
X90623Y-1062083D01*
X90940Y-1061667D01*
X91067Y-1061167D01*
X90940Y-1060667D01*
X90623Y-1060250D01*
X90053Y-1060000D01*
X89483Y-1060083D01*
X88913Y-1060417D01*
G01X93697Y-1060833D02*
X94077Y-1060333D01*
X94520Y-1060083D01*
X95027Y-1060000D01*
X95660Y-1060167D01*
X96103Y-1060583D01*
X96230Y-1061083D01*
X96167Y-1061583D01*
X95913Y-1062000D01*
X94647Y-1062833D01*
X94077Y-1063417D01*
X93697Y-1064250D01*
X93570Y-1065000D01*
X96230D01*
G01X99873D02*
X100000Y-1063917D01*
X100190Y-1063000D01*
X100443Y-1062167D01*
X100760Y-1061250D01*
X101267Y-1060000D01*
X98733D01*
G01X104277Y-1063333D02*
X105923D01*
G01X108997Y-1060833D02*
X109377Y-1060333D01*
X109820Y-1060083D01*
X110327Y-1060000D01*
X110960Y-1060167D01*
X111403Y-1060583D01*
X111530Y-1061083D01*
X111467Y-1061583D01*
X111213Y-1062000D01*
X109947Y-1062833D01*
X109377Y-1063417D01*
X108997Y-1064250D01*
X108870Y-1065000D01*
X111530D01*
G01X113907Y-1064000D02*
X114287Y-1064583D01*
X114793Y-1064917D01*
X115363Y-1065000D01*
X115870Y-1064917D01*
X116377Y-1064500D01*
X116693Y-1064000D01*
X116757Y-1063500D01*
X116630Y-1062917D01*
X116187Y-1062500D01*
X115743Y-1062333D01*
X115173D01*
G01X115743D02*
X116123Y-1062083D01*
X116440Y-1061667D01*
X116567Y-1061167D01*
X116440Y-1060667D01*
X116123Y-1060250D01*
X115553Y-1060000D01*
X114983Y-1060083D01*
X114413Y-1060417D01*
G01X121160Y-1065000D02*
Y-1060000D01*
X118817Y-1063583D01*
X121983D01*
G01X124107Y-1064250D02*
X124487Y-1064667D01*
X124930Y-1064917D01*
X125500Y-1065000D01*
X126070Y-1064833D01*
X126513Y-1064500D01*
X126830Y-1063917D01*
X126893Y-1063250D01*
X126767Y-1062583D01*
X126450Y-1062167D01*
X126007Y-1061833D01*
X125563Y-1061750D01*
X125120Y-1061833D01*
X124550Y-1062167D01*
X124740Y-1060000D01*
X126450D01*
G01X134497Y-1065000D02*
Y-1060000D01*
X136903D01*
G01X136017Y-1062417D02*
X134497D01*
G01X139217Y-1065000D02*
X140800Y-1060000D01*
X142383Y-1065000D01*
G01X141813Y-1063250D02*
X139787D01*
G01X144570Y-1065000D02*
X147230Y-1060000D01*
G01X144570D02*
X147230Y-1065000D01*
G01X151000Y-1065167D02*
X150873Y-1065083D01*
Y-1064917D01*
X151000Y-1064833D01*
X151127Y-1064917D01*
Y-1065083D01*
X151000Y-1065167D01*
G01Y-1062917D02*
X150873Y-1062833D01*
Y-1062667D01*
X151000Y-1062583D01*
X151127Y-1062667D01*
Y-1062833D01*
X151000Y-1062917D01*
G01X155783Y-1066667D02*
X155150Y-1065833D01*
X154833Y-1065000D01*
Y-1061667D01*
X155150Y-1060833D01*
X155783Y-1060000D01*
G01X161200D02*
X160693Y-1060167D01*
X160313Y-1060583D01*
X160060Y-1061083D01*
X159870Y-1061750D01*
X159807Y-1062500D01*
X159870Y-1063250D01*
X160060Y-1063917D01*
X160313Y-1064417D01*
X160693Y-1064833D01*
X161200Y-1065000D01*
X161707Y-1064833D01*
X162087Y-1064417D01*
X162340Y-1063917D01*
X162530Y-1063250D01*
X162593Y-1062500D01*
X162530Y-1061750D01*
X162340Y-1061083D01*
X162087Y-1060583D01*
X161707Y-1060167D01*
X161200Y-1060000D01*
G01X164907Y-1064000D02*
X165287Y-1064583D01*
X165793Y-1064917D01*
X166363Y-1065000D01*
X166870Y-1064917D01*
X167377Y-1064500D01*
X167693Y-1064000D01*
X167757Y-1063500D01*
X167630Y-1062917D01*
X167187Y-1062500D01*
X166743Y-1062333D01*
X166173D01*
G01X166743D02*
X167123Y-1062083D01*
X167440Y-1061667D01*
X167567Y-1061167D01*
X167440Y-1060667D01*
X167123Y-1060250D01*
X166553Y-1060000D01*
X165983Y-1060083D01*
X165413Y-1060417D01*
G01X171717Y-1066667D02*
X172350Y-1065833D01*
X172667Y-1065000D01*
Y-1061667D01*
X172350Y-1060833D01*
X171717Y-1060000D01*
G01X175107Y-1064000D02*
X175487Y-1064583D01*
X175993Y-1064917D01*
X176563Y-1065000D01*
X177070Y-1064917D01*
X177577Y-1064500D01*
X177893Y-1064000D01*
X177957Y-1063500D01*
X177830Y-1062917D01*
X177387Y-1062500D01*
X176943Y-1062333D01*
X176373D01*
G01X176943D02*
X177323Y-1062083D01*
X177640Y-1061667D01*
X177767Y-1061167D01*
X177640Y-1060667D01*
X177323Y-1060250D01*
X176753Y-1060000D01*
X176183Y-1060083D01*
X175613Y-1060417D01*
G01X180523Y-1064417D02*
X180967Y-1064833D01*
X181473Y-1065000D01*
X181980Y-1064833D01*
X182423Y-1064333D01*
X182740Y-1063583D01*
X182867Y-1062833D01*
Y-1061917D01*
X182740Y-1061167D01*
X182423Y-1060500D01*
X182043Y-1060167D01*
X181600Y-1060000D01*
X181093Y-1060167D01*
X180713Y-1060500D01*
X180460Y-1061000D01*
X180333Y-1061667D01*
X180460Y-1062250D01*
X180777Y-1062833D01*
X181157Y-1063167D01*
X181600Y-1063250D01*
X182107Y-1063083D01*
X182487Y-1062667D01*
X182867Y-1061917D01*
G01X186573Y-1065000D02*
X186700Y-1063917D01*
X186890Y-1063000D01*
X187143Y-1062167D01*
X187460Y-1061250D01*
X187967Y-1060000D01*
X185433D01*
G01X190977Y-1063333D02*
X192623D01*
G01X195507Y-1064000D02*
X195887Y-1064583D01*
X196393Y-1064917D01*
X196963Y-1065000D01*
X197470Y-1064917D01*
X197977Y-1064500D01*
X198293Y-1064000D01*
X198357Y-1063500D01*
X198230Y-1062917D01*
X197787Y-1062500D01*
X197343Y-1062333D01*
X196773D01*
G01X197343D02*
X197723Y-1062083D01*
X198040Y-1061667D01*
X198167Y-1061167D01*
X198040Y-1060667D01*
X197723Y-1060250D01*
X197153Y-1060000D01*
X196583Y-1060083D01*
X196013Y-1060417D01*
G01X200797Y-1062917D02*
X201240Y-1062333D01*
X201620Y-1062000D01*
X202127Y-1061833D01*
X202570Y-1062000D01*
X202887Y-1062333D01*
X203140Y-1062833D01*
X203203Y-1063417D01*
X203140Y-1063917D01*
X202887Y-1064417D01*
X202507Y-1064833D01*
X202063Y-1065000D01*
X201557Y-1064833D01*
X201113Y-1064333D01*
X200860Y-1063583D01*
X200797Y-1062750D01*
X200923Y-1061667D01*
X201113Y-1061083D01*
X201430Y-1060500D01*
X201873Y-1060083D01*
X202317Y-1060000D01*
X202760Y-1060167D01*
X203077Y-1060583D01*
G01X207100Y-1065000D02*
Y-1060000D01*
X206340Y-1061000D01*
G01Y-1065000D02*
X207860D01*
G01X212960D02*
Y-1060000D01*
X210617Y-1063583D01*
X213783D01*
G01X232000Y-995000D02*
Y-1070000D01*
G01Y-1045000D02*
X335000D01*
Y-1020000D01*
G01X232000D02*
X335000D01*
G01X337000Y-995000D02*
Y-1070000D01*
G01X335000Y-995000D02*
Y-1070000D01*
G01X342507Y-1055000D02*
Y-1050000D01*
X343773D01*
X344280Y-1050250D01*
X344660Y-1050583D01*
X344977Y-1051083D01*
X345230Y-1051667D01*
X345293Y-1052500D01*
X345230Y-1053333D01*
X344977Y-1053917D01*
X344660Y-1054417D01*
X344280Y-1054750D01*
X343773Y-1055000D01*
X342507D01*
G01X347417D02*
X349000Y-1050000D01*
X350583Y-1055000D01*
G01X350013Y-1053250D02*
X347987D01*
G01X354100Y-1050000D02*
Y-1055000D01*
G01X352643Y-1050000D02*
X355557D01*
G01X360467Y-1055000D02*
X357933D01*
Y-1050000D01*
X360467D01*
G01X359453Y-1052417D02*
X357933D01*
G01X364300Y-1055167D02*
X364173Y-1055083D01*
Y-1054917D01*
X364300Y-1054833D01*
X364427Y-1054917D01*
Y-1055083D01*
X364300Y-1055167D01*
G01Y-1052917D02*
X364173Y-1052833D01*
Y-1052667D01*
X364300Y-1052583D01*
X364427Y-1052667D01*
Y-1052833D01*
X364300Y-1052917D01*
G01X337000Y-1045000D02*
X537000D01*
G01X342633Y-1030000D02*
Y-1025000D01*
X344153D01*
X344660Y-1025250D01*
X345040Y-1025833D01*
X345167Y-1026500D01*
X345040Y-1027167D01*
X344723Y-1027667D01*
X344153Y-1027917D01*
X342633D01*
G01X347860Y-1030167D02*
X350140Y-1025000D01*
G01X352643Y-1030000D02*
Y-1025000D01*
X355557Y-1030000D01*
Y-1025000D01*
G01X359200Y-1030167D02*
X359073Y-1030083D01*
Y-1029917D01*
X359200Y-1029833D01*
X359327Y-1029917D01*
Y-1030083D01*
X359200Y-1030167D01*
G01Y-1027917D02*
X359073Y-1027833D01*
Y-1027667D01*
X359200Y-1027583D01*
X359327Y-1027667D01*
Y-1027833D01*
X359200Y-1027917D01*
G01X342633Y-1005000D02*
Y-1000000D01*
X344153D01*
X344660Y-1000250D01*
X345040Y-1000833D01*
X345167Y-1001500D01*
X345040Y-1002167D01*
X344723Y-1002667D01*
X344153Y-1002917D01*
X342633D01*
G01X347733Y-1005000D02*
Y-1000000D01*
X349317D01*
X349823Y-1000250D01*
X350140Y-1000583D01*
X350267Y-1001250D01*
X350140Y-1001917D01*
X349760Y-1002333D01*
X349317Y-1002583D01*
X347733D01*
G01X349317D02*
X350267Y-1005000D01*
G01X354100D02*
X353593Y-1004917D01*
X353150Y-1004583D01*
X352770Y-1004083D01*
X352517Y-1003500D01*
X352390Y-1002833D01*
Y-1002167D01*
X352517Y-1001500D01*
X352770Y-1000917D01*
X353150Y-1000417D01*
X353593Y-1000083D01*
X354100Y-1000000D01*
X354607Y-1000083D01*
X355050Y-1000417D01*
X355430Y-1000917D01*
X355683Y-1001500D01*
X355810Y-1002167D01*
Y-1002833D01*
X355683Y-1003500D01*
X355430Y-1004083D01*
X355050Y-1004583D01*
X354607Y-1004917D01*
X354100Y-1005000D01*
G01X357933Y-1004000D02*
X358250Y-1004500D01*
X358630Y-1004833D01*
X359073Y-1005000D01*
X359580Y-1004833D01*
X359960Y-1004500D01*
X360340Y-1004000D01*
X360467Y-1003333D01*
Y-1000000D01*
G01X365567Y-1005000D02*
X363033D01*
Y-1000000D01*
X365567D01*
G01X364553Y-1002417D02*
X363033D01*
G01X370793Y-1000417D02*
X370413Y-1000167D01*
X369970Y-1000000D01*
X369463D01*
X368893Y-1000250D01*
X368450Y-1000667D01*
X368133Y-1001167D01*
X367880Y-1002000D01*
X367817Y-1002750D01*
X367943Y-1003500D01*
X368133Y-1004000D01*
X368513Y-1004500D01*
X368957Y-1004833D01*
X369400Y-1005000D01*
X369843D01*
X370287Y-1004833D01*
X370667Y-1004583D01*
X370983Y-1004250D01*
G01X374500Y-1000000D02*
Y-1005000D01*
G01X373043Y-1000000D02*
X375957D01*
G01X379600Y-1005167D02*
X379473Y-1005083D01*
Y-1004917D01*
X379600Y-1004833D01*
X379727Y-1004917D01*
Y-1005083D01*
X379600Y-1005167D01*
G01Y-1002917D02*
X379473Y-1002833D01*
Y-1002667D01*
X379600Y-1002583D01*
X379727Y-1002667D01*
Y-1002833D01*
X379600Y-1002917D01*
G01X337000Y-1020000D02*
X537000D01*
G01X452000Y-1045000D02*
Y-1070000D01*
G01X454633Y-1047500D02*
Y-1052500D01*
X457167D01*
G01X460240Y-1047500D02*
X461760D01*
G01X461000D02*
Y-1052500D01*
G01X460240D02*
X461760D01*
G01X466607Y-1049833D02*
X466860Y-1049583D01*
X467050Y-1049167D01*
X467177Y-1048583D01*
X467050Y-1048083D01*
X466797Y-1047750D01*
X466353Y-1047500D01*
X464643D01*
Y-1052500D01*
X466733D01*
X467177Y-1052167D01*
X467430Y-1051667D01*
X467557Y-1051083D01*
X467430Y-1050500D01*
X467050Y-1050000D01*
X466607Y-1049833D01*
X464643D01*
G01X471200Y-1052667D02*
X471073Y-1052583D01*
Y-1052417D01*
X471200Y-1052333D01*
X471327Y-1052417D01*
Y-1052583D01*
X471200Y-1052667D01*
G01Y-1050417D02*
X471073Y-1050333D01*
Y-1050167D01*
X471200Y-1050083D01*
X471327Y-1050167D01*
Y-1050333D01*
X471200Y-1050417D01*
G01X495000Y-1045000D02*
Y-1070000D01*
G01X498900Y-1047500D02*
Y-1052500D01*
G01X497443Y-1047500D02*
X500357D01*
G01X504000Y-1052500D02*
X503620Y-1052417D01*
X503240Y-1052083D01*
X502987Y-1051500D01*
X502860Y-1050833D01*
X502987Y-1050167D01*
X503240Y-1049583D01*
X503620Y-1049250D01*
X504000Y-1049167D01*
X504380Y-1049250D01*
X504760Y-1049583D01*
X505013Y-1050167D01*
X505077Y-1050833D01*
X505013Y-1051500D01*
X504760Y-1052083D01*
X504380Y-1052417D01*
X504000Y-1052500D01*
G01X509100D02*
X508720Y-1052417D01*
X508340Y-1052083D01*
X508087Y-1051500D01*
X507960Y-1050833D01*
X508087Y-1050167D01*
X508340Y-1049583D01*
X508720Y-1049250D01*
X509100Y-1049167D01*
X509480Y-1049250D01*
X509860Y-1049583D01*
X510113Y-1050167D01*
X510177Y-1050833D01*
X510113Y-1051500D01*
X509860Y-1052083D01*
X509480Y-1052417D01*
X509100Y-1052500D01*
G01X514200D02*
Y-1047500D01*
G01X519300Y-1052667D02*
X519173Y-1052583D01*
Y-1052417D01*
X519300Y-1052333D01*
X519427Y-1052417D01*
Y-1052583D01*
X519300Y-1052667D01*
G01Y-1050417D02*
X519173Y-1050333D01*
Y-1050167D01*
X519300Y-1050083D01*
X519427Y-1050167D01*
Y-1050333D01*
X519300Y-1050417D01*
G01X495000Y-1020000D02*
Y-1045000D01*
G01X497633Y-1027500D02*
Y-1022500D01*
X499217D01*
X499723Y-1022750D01*
X500040Y-1023083D01*
X500167Y-1023750D01*
X500040Y-1024417D01*
X499660Y-1024833D01*
X499217Y-1025083D01*
X497633D01*
G01X499217D02*
X500167Y-1027500D01*
G01X505267D02*
X502733D01*
Y-1022500D01*
X505267D01*
G01X504253Y-1024917D02*
X502733D01*
G01X507517Y-1022500D02*
X509100Y-1027500D01*
X510683Y-1022500D01*
G01X514200Y-1027667D02*
X514073Y-1027583D01*
Y-1027417D01*
X514200Y-1027333D01*
X514327Y-1027417D01*
Y-1027583D01*
X514200Y-1027667D01*
G01Y-1025417D02*
X514073Y-1025333D01*
Y-1025167D01*
X514200Y-1025083D01*
X514327Y-1025167D01*
Y-1025333D01*
X514200Y-1025417D01*
G01X503013Y-1073167D02*
X503120Y-1073042D01*
X503200Y-1072833D01*
X503253Y-1072542D01*
X503200Y-1072292D01*
X503093Y-1072125D01*
X502907Y-1072000D01*
X502187D01*
Y-1074500D01*
X503067D01*
X503253Y-1074333D01*
X503360Y-1074083D01*
X503413Y-1073792D01*
X503360Y-1073500D01*
X503200Y-1073250D01*
X503013Y-1073167D01*
X502187D01*
G01X505480Y-1074500D02*
Y-1072833D01*
G01Y-1073125D02*
X505373Y-1072958D01*
X505213Y-1072875D01*
X505027Y-1072833D01*
X504840Y-1072917D01*
X504680Y-1073083D01*
X504573Y-1073333D01*
X504520Y-1073667D01*
X504573Y-1074000D01*
X504680Y-1074250D01*
X504840Y-1074417D01*
X505027Y-1074500D01*
X505213Y-1074458D01*
X505373Y-1074333D01*
X505480Y-1074167D01*
G01X506800Y-1074208D02*
X506933Y-1074375D01*
X507120Y-1074500D01*
X507280D01*
X507440Y-1074417D01*
X507547Y-1074292D01*
X507600Y-1074125D01*
X507573Y-1073875D01*
X507467Y-1073750D01*
X506987Y-1073500D01*
X506880Y-1073208D01*
X506933Y-1073000D01*
X507040Y-1072875D01*
X507200Y-1072833D01*
X507360Y-1072875D01*
X507520Y-1073000D01*
G01X509000Y-1073375D02*
X509853D01*
X509773Y-1073083D01*
X509640Y-1072917D01*
X509453Y-1072833D01*
X509267Y-1072875D01*
X509107Y-1073000D01*
X509000Y-1073292D01*
X508947Y-1073542D01*
Y-1073792D01*
X509000Y-1074042D01*
X509133Y-1074292D01*
X509293Y-1074458D01*
X509480Y-1074500D01*
X509667Y-1074417D01*
X509853Y-1074167D01*
G01X511120Y-1074500D02*
Y-1072000D01*
G01Y-1073250D02*
X511253Y-1073000D01*
X511413Y-1072875D01*
X511573Y-1072833D01*
X511813Y-1072917D01*
X511973Y-1073083D01*
X512080Y-1073375D01*
Y-1073708D01*
X512027Y-1074042D01*
X511920Y-1074292D01*
X511733Y-1074458D01*
X511573Y-1074500D01*
X511413Y-1074458D01*
X511253Y-1074333D01*
X511120Y-1074125D01*
G01X513800Y-1074500D02*
X513640Y-1074458D01*
X513480Y-1074292D01*
X513373Y-1074000D01*
X513320Y-1073667D01*
X513373Y-1073333D01*
X513480Y-1073042D01*
X513640Y-1072875D01*
X513800Y-1072833D01*
X513960Y-1072875D01*
X514120Y-1073042D01*
X514227Y-1073333D01*
X514253Y-1073667D01*
X514227Y-1074000D01*
X514120Y-1074292D01*
X513960Y-1074458D01*
X513800Y-1074500D01*
G01X516480D02*
Y-1072833D01*
G01Y-1073125D02*
X516373Y-1072958D01*
X516213Y-1072875D01*
X516027Y-1072833D01*
X515840Y-1072917D01*
X515680Y-1073083D01*
X515573Y-1073333D01*
X515520Y-1073667D01*
X515573Y-1074000D01*
X515680Y-1074250D01*
X515840Y-1074417D01*
X516027Y-1074500D01*
X516213Y-1074458D01*
X516373Y-1074333D01*
X516480Y-1074167D01*
G01X517827Y-1074500D02*
Y-1072833D01*
G01Y-1073167D02*
X517960Y-1073000D01*
X518093Y-1072875D01*
X518280Y-1072833D01*
X518413Y-1072875D01*
X518573Y-1073000D01*
G01X520880Y-1072000D02*
Y-1074500D01*
G01Y-1074125D02*
X520773Y-1074333D01*
X520613Y-1074458D01*
X520427Y-1074500D01*
X520213Y-1074417D01*
X520053Y-1074208D01*
X519947Y-1073958D01*
X519920Y-1073667D01*
X519947Y-1073375D01*
X520053Y-1073125D01*
X520213Y-1072917D01*
X520427Y-1072833D01*
X520613Y-1072875D01*
X520747Y-1072958D01*
X520880Y-1073125D01*
G01X524267Y-1074500D02*
Y-1072000D01*
X524933D01*
X525147Y-1072125D01*
X525280Y-1072292D01*
X525333Y-1072625D01*
X525280Y-1072958D01*
X525120Y-1073167D01*
X524933Y-1073292D01*
X524267D01*
G01X524933D02*
X525333Y-1074500D01*
G01X526600Y-1073375D02*
X527453D01*
X527373Y-1073083D01*
X527240Y-1072917D01*
X527053Y-1072833D01*
X526867Y-1072875D01*
X526707Y-1073000D01*
X526600Y-1073292D01*
X526547Y-1073542D01*
Y-1073792D01*
X526600Y-1074042D01*
X526733Y-1074292D01*
X526893Y-1074458D01*
X527080Y-1074500D01*
X527267Y-1074417D01*
X527453Y-1074167D01*
G01X528720Y-1072833D02*
X529200Y-1074500D01*
X529680Y-1072833D01*
G01X531400Y-1074583D02*
X531347Y-1074542D01*
Y-1074458D01*
X531400Y-1074417D01*
X531453Y-1074458D01*
Y-1074542D01*
X531400Y-1074583D01*
G01X533600Y-1074500D02*
X533787Y-1074458D01*
X534000Y-1074333D01*
X534133Y-1074125D01*
X534187Y-1073833D01*
X534133Y-1073542D01*
X533973Y-1073292D01*
X533733Y-1073167D01*
X533467D01*
X533307Y-1073083D01*
X533173Y-1072875D01*
X533120Y-1072583D01*
X533200Y-1072292D01*
X533387Y-1072083D01*
X533600Y-1072000D01*
X533813Y-1072083D01*
X534000Y-1072292D01*
X534080Y-1072583D01*
X534027Y-1072875D01*
X533893Y-1073083D01*
X533733Y-1073167D01*
X533467D01*
X533227Y-1073292D01*
X533067Y-1073542D01*
X533013Y-1073833D01*
X533067Y-1074125D01*
X533200Y-1074333D01*
X533413Y-1074458D01*
X533600Y-1074500D01*
G01X536013Y-1073167D02*
X536120Y-1073042D01*
X536200Y-1072833D01*
X536253Y-1072542D01*
X536200Y-1072292D01*
X536093Y-1072125D01*
X535907Y-1072000D01*
X535187D01*
Y-1074500D01*
X536067D01*
X536253Y-1074333D01*
X536360Y-1074083D01*
X536413Y-1073792D01*
X536360Y-1073500D01*
X536200Y-1073250D01*
X536013Y-1073167D01*
X535187D01*
G01X-457143Y-1211429D02*
Y2242857D01*
X4308572D01*
Y-1211429D01*
X-457143D01*
G01X71650Y-1024800D02*
X69130Y-1024383D01*
X66925Y-1022717D01*
X65035Y-1020217D01*
X63775Y-1017300D01*
X63145Y-1013967D01*
Y-1010633D01*
X63775Y-1007300D01*
X65035Y-1004383D01*
X66925Y-1001884D01*
X69130Y-1000217D01*
X71650Y-999800D01*
X74170Y-1000217D01*
X76375Y-1001884D01*
X78265Y-1004383D01*
X79525Y-1007300D01*
X80155Y-1010633D01*
Y-1013967D01*
X79525Y-1017300D01*
X78265Y-1020217D01*
X76375Y-1022717D01*
X74170Y-1024383D01*
X71650Y-1024800D01*
G01X74170Y-1018133D02*
X77950Y-1024800D01*
G01X91495Y-1008134D02*
Y-1019800D01*
X92755Y-1022717D01*
X94645Y-1024383D01*
X96850Y-1024800D01*
X99055Y-1024383D01*
X100945Y-1022717D01*
X102205Y-1019800D01*
G01Y-1024800D02*
Y-1008134D01*
G01X127720Y-1024800D02*
Y-1008134D01*
G01Y-1011050D02*
X126460Y-1009384D01*
X124570Y-1008550D01*
X122365Y-1008134D01*
X120160Y-1008967D01*
X118270Y-1010633D01*
X117010Y-1013134D01*
X116380Y-1016467D01*
X117010Y-1019800D01*
X118270Y-1022301D01*
X120160Y-1023967D01*
X122365Y-1024800D01*
X124570Y-1024383D01*
X126460Y-1023134D01*
X127720Y-1021467D01*
G01X141895Y-1024800D02*
Y-1008134D01*
G01Y-1012300D02*
X143155Y-1010217D01*
X145045Y-1008550D01*
X147565Y-1008134D01*
X149770Y-1008550D01*
X151660Y-1010217D01*
X152605Y-1013134D01*
Y-1024800D01*
G01X172450Y-999800D02*
Y-1024800D01*
G01X168040Y-1008134D02*
X176860D01*
G01X203320Y-1024800D02*
Y-1008134D01*
G01Y-1011050D02*
X202060Y-1009384D01*
X200170Y-1008550D01*
X197965Y-1008134D01*
X195760Y-1008967D01*
X193870Y-1010633D01*
X192610Y-1013134D01*
X191980Y-1016467D01*
X192610Y-1019800D01*
X193870Y-1022301D01*
X195760Y-1023967D01*
X197965Y-1024800D01*
X200170Y-1024383D01*
X202060Y-1023134D01*
X203320Y-1021467D01*
G01X49820Y-1042350D02*
X51387D01*
Y-1044240D01*
X50917Y-1044870D01*
X50368Y-1045290D01*
X49585Y-1045500D01*
X48802Y-1045290D01*
X48253Y-1044870D01*
X47783Y-1044240D01*
X47470Y-1043505D01*
X47313Y-1042665D01*
Y-1041930D01*
X47470Y-1041300D01*
X47783Y-1040565D01*
X48253Y-1039935D01*
X48723Y-1039515D01*
X49350Y-1039200D01*
X49898D01*
X50525Y-1039410D01*
X50995Y-1039830D01*
G01X53927Y-1039200D02*
Y-1043715D01*
X54240Y-1044660D01*
X54867Y-1045290D01*
X55650Y-1045500D01*
X56433Y-1045290D01*
X57060Y-1044660D01*
X57373Y-1043715D01*
Y-1039200D01*
G01X61010D02*
X62890D01*
G01X61950D02*
Y-1045500D01*
G01X61010D02*
X62890D01*
G01X66605Y-1044660D02*
X67232Y-1045185D01*
X67937Y-1045500D01*
X68563D01*
X69190Y-1045185D01*
X69660Y-1044660D01*
X69895Y-1043925D01*
X69738Y-1043190D01*
X69347Y-1042560D01*
X68642Y-1042140D01*
X67702Y-1041930D01*
X67153Y-1041510D01*
X66918Y-1040775D01*
X67075Y-1040040D01*
X67467Y-1039515D01*
X68015Y-1039200D01*
X68563D01*
X69112Y-1039410D01*
X69582Y-1039935D01*
G01X72905Y-1045500D02*
Y-1039200D01*
G01X76195D02*
Y-1045500D01*
G01Y-1042350D02*
X72905D01*
G01X78892Y-1045500D02*
X80850Y-1039200D01*
X82808Y-1045500D01*
G01X82103Y-1043295D02*
X79597D01*
G01X85348Y-1045500D02*
Y-1039200D01*
X88952Y-1045500D01*
Y-1039200D01*
G01X98027Y-1045500D02*
Y-1039200D01*
X99593D01*
X100220Y-1039515D01*
X100690Y-1039935D01*
X101082Y-1040565D01*
X101395Y-1041300D01*
X101473Y-1042350D01*
X101395Y-1043400D01*
X101082Y-1044135D01*
X100690Y-1044765D01*
X100220Y-1045185D01*
X99593Y-1045500D01*
X98027D01*
G01X105110Y-1039200D02*
X106990D01*
G01X106050D02*
Y-1045500D01*
G01X105110D02*
X106990D01*
G01X110705Y-1044660D02*
X111332Y-1045185D01*
X112037Y-1045500D01*
X112663D01*
X113290Y-1045185D01*
X113760Y-1044660D01*
X113995Y-1043925D01*
X113838Y-1043190D01*
X113447Y-1042560D01*
X112742Y-1042140D01*
X111802Y-1041930D01*
X111253Y-1041510D01*
X111018Y-1040775D01*
X111175Y-1040040D01*
X111567Y-1039515D01*
X112115Y-1039200D01*
X112663D01*
X113212Y-1039410D01*
X113682Y-1039935D01*
G01X118650Y-1039200D02*
Y-1045500D01*
G01X116848Y-1039200D02*
X120452D01*
G01X124950Y-1045710D02*
X124793Y-1045605D01*
Y-1045395D01*
X124950Y-1045290D01*
X125107Y-1045395D01*
Y-1045605D01*
X124950Y-1045710D01*
G01X131093Y-1046655D02*
X131407Y-1045290D01*
G01X137550Y-1039200D02*
Y-1045500D01*
G01X135748Y-1039200D02*
X139352D01*
G01X141892Y-1045500D02*
X143850Y-1039200D01*
X145808Y-1045500D01*
G01X145103Y-1043295D02*
X142597D01*
G01X150150Y-1045500D02*
X149523Y-1045395D01*
X148975Y-1044975D01*
X148505Y-1044345D01*
X148192Y-1043610D01*
X148035Y-1042770D01*
Y-1041930D01*
X148192Y-1041090D01*
X148505Y-1040355D01*
X148975Y-1039725D01*
X149523Y-1039305D01*
X150150Y-1039200D01*
X150777Y-1039305D01*
X151325Y-1039725D01*
X151795Y-1040355D01*
X152108Y-1041090D01*
X152265Y-1041930D01*
Y-1042770D01*
X152108Y-1043610D01*
X151795Y-1044345D01*
X151325Y-1044975D01*
X150777Y-1045395D01*
X150150Y-1045500D01*
G01X156450D02*
Y-1042665D01*
X154883Y-1039200D01*
G01X158017D02*
X156450Y-1042665D01*
G01X161027Y-1039200D02*
Y-1043715D01*
X161340Y-1044660D01*
X161967Y-1045290D01*
X162750Y-1045500D01*
X163533Y-1045290D01*
X164160Y-1044660D01*
X164473Y-1043715D01*
Y-1039200D01*
G01X167092Y-1045500D02*
X169050Y-1039200D01*
X171008Y-1045500D01*
G01X170303Y-1043295D02*
X167797D01*
G01X173548Y-1045500D02*
Y-1039200D01*
X177152Y-1045500D01*
Y-1039200D01*
G01X51073Y-1049725D02*
X50603Y-1049410D01*
X50055Y-1049200D01*
X49428D01*
X48723Y-1049515D01*
X48175Y-1050040D01*
X47783Y-1050670D01*
X47470Y-1051720D01*
X47392Y-1052665D01*
X47548Y-1053610D01*
X47783Y-1054240D01*
X48253Y-1054870D01*
X48802Y-1055290D01*
X49350Y-1055500D01*
X49898D01*
X50447Y-1055290D01*
X50917Y-1054975D01*
X51308Y-1054555D01*
G01X54710Y-1049200D02*
X56590D01*
G01X55650D02*
Y-1055500D01*
G01X54710D02*
X56590D01*
G01X61950Y-1049200D02*
Y-1055500D01*
G01X60148Y-1049200D02*
X63752D01*
G01X68250Y-1055500D02*
Y-1052665D01*
X66683Y-1049200D01*
G01X69817D02*
X68250Y-1052665D01*
G01X79127Y-1054240D02*
X79597Y-1054975D01*
X80223Y-1055395D01*
X80928Y-1055500D01*
X81555Y-1055395D01*
X82182Y-1054870D01*
X82573Y-1054240D01*
X82652Y-1053610D01*
X82495Y-1052875D01*
X81947Y-1052350D01*
X81398Y-1052140D01*
X80693D01*
G01X81398D02*
X81868Y-1051825D01*
X82260Y-1051300D01*
X82417Y-1050670D01*
X82260Y-1050040D01*
X81868Y-1049515D01*
X81163Y-1049200D01*
X80458Y-1049305D01*
X79753Y-1049725D01*
G01X85427Y-1054240D02*
X85897Y-1054975D01*
X86523Y-1055395D01*
X87228Y-1055500D01*
X87855Y-1055395D01*
X88482Y-1054870D01*
X88873Y-1054240D01*
X88952Y-1053610D01*
X88795Y-1052875D01*
X88247Y-1052350D01*
X87698Y-1052140D01*
X86993D01*
G01X87698D02*
X88168Y-1051825D01*
X88560Y-1051300D01*
X88717Y-1050670D01*
X88560Y-1050040D01*
X88168Y-1049515D01*
X87463Y-1049200D01*
X86758Y-1049305D01*
X86053Y-1049725D01*
G01X91727Y-1054240D02*
X92197Y-1054975D01*
X92823Y-1055395D01*
X93528Y-1055500D01*
X94155Y-1055395D01*
X94782Y-1054870D01*
X95173Y-1054240D01*
X95252Y-1053610D01*
X95095Y-1052875D01*
X94547Y-1052350D01*
X93998Y-1052140D01*
X93293D01*
G01X93998D02*
X94468Y-1051825D01*
X94860Y-1051300D01*
X95017Y-1050670D01*
X94860Y-1050040D01*
X94468Y-1049515D01*
X93763Y-1049200D01*
X93058Y-1049305D01*
X92353Y-1049725D01*
G01X99593Y-1055500D02*
X99750Y-1054135D01*
X99985Y-1052980D01*
X100298Y-1051930D01*
X100690Y-1050775D01*
X101317Y-1049200D01*
X98183D01*
G01X105893Y-1055500D02*
X106050Y-1054135D01*
X106285Y-1052980D01*
X106598Y-1051930D01*
X106990Y-1050775D01*
X107617Y-1049200D01*
X104483D01*
G01X112193Y-1056655D02*
X112507Y-1055290D01*
G01X118650Y-1049200D02*
Y-1055500D01*
G01X116848Y-1049200D02*
X120452D01*
G01X122992Y-1055500D02*
X124950Y-1049200D01*
X126908Y-1055500D01*
G01X126203Y-1053295D02*
X123697D01*
G01X130310Y-1049200D02*
X132190D01*
G01X131250D02*
Y-1055500D01*
G01X130310D02*
X132190D01*
G01X135200Y-1049200D02*
X136297Y-1055500D01*
X137550Y-1049200D01*
X138803Y-1055500D01*
X139900Y-1049200D01*
G01X141892Y-1055500D02*
X143850Y-1049200D01*
X145808Y-1055500D01*
G01X145103Y-1053295D02*
X142597D01*
G01X148348Y-1055500D02*
Y-1049200D01*
X151952Y-1055500D01*
Y-1049200D01*
G01X162358Y-1057600D02*
X161575Y-1056550D01*
X161183Y-1055500D01*
Y-1051300D01*
X161575Y-1050250D01*
X162358Y-1049200D01*
G01X173783Y-1055500D02*
Y-1049200D01*
X175742D01*
X176368Y-1049515D01*
X176760Y-1049935D01*
X176917Y-1050775D01*
X176760Y-1051615D01*
X176290Y-1052140D01*
X175742Y-1052455D01*
X173783D01*
G01X175742D02*
X176917Y-1055500D01*
G01X181650Y-1055710D02*
X181493Y-1055605D01*
Y-1055395D01*
X181650Y-1055290D01*
X181807Y-1055395D01*
Y-1055605D01*
X181650Y-1055710D01*
G01X187950Y-1055500D02*
X187323Y-1055395D01*
X186775Y-1054975D01*
X186305Y-1054345D01*
X185992Y-1053610D01*
X185835Y-1052770D01*
Y-1051930D01*
X185992Y-1051090D01*
X186305Y-1050355D01*
X186775Y-1049725D01*
X187323Y-1049305D01*
X187950Y-1049200D01*
X188577Y-1049305D01*
X189125Y-1049725D01*
X189595Y-1050355D01*
X189908Y-1051090D01*
X190065Y-1051930D01*
Y-1052770D01*
X189908Y-1053610D01*
X189595Y-1054345D01*
X189125Y-1054975D01*
X188577Y-1055395D01*
X187950Y-1055500D01*
G01X194250Y-1055710D02*
X194093Y-1055605D01*
Y-1055395D01*
X194250Y-1055290D01*
X194407Y-1055395D01*
Y-1055605D01*
X194250Y-1055710D01*
G01X202273Y-1049725D02*
X201803Y-1049410D01*
X201255Y-1049200D01*
X200628D01*
X199923Y-1049515D01*
X199375Y-1050040D01*
X198983Y-1050670D01*
X198670Y-1051720D01*
X198592Y-1052665D01*
X198748Y-1053610D01*
X198983Y-1054240D01*
X199453Y-1054870D01*
X200002Y-1055290D01*
X200550Y-1055500D01*
X201098D01*
X201647Y-1055290D01*
X202117Y-1054975D01*
X202508Y-1054555D01*
G01X206850Y-1055710D02*
X206693Y-1055605D01*
Y-1055395D01*
X206850Y-1055290D01*
X207007Y-1055395D01*
Y-1055605D01*
X206850Y-1055710D01*
G01X213542Y-1057600D02*
X214325Y-1056550D01*
X214717Y-1055500D01*
Y-1051300D01*
X214325Y-1050250D01*
X213542Y-1049200D01*
G01X47548Y-1035500D02*
Y-1029200D01*
X51152Y-1035500D01*
Y-1029200D01*
G01X55650Y-1035500D02*
X55023Y-1035395D01*
X54475Y-1034975D01*
X54005Y-1034345D01*
X53692Y-1033610D01*
X53535Y-1032770D01*
Y-1031930D01*
X53692Y-1031090D01*
X54005Y-1030355D01*
X54475Y-1029725D01*
X55023Y-1029305D01*
X55650Y-1029200D01*
X56277Y-1029305D01*
X56825Y-1029725D01*
X57295Y-1030355D01*
X57608Y-1031090D01*
X57765Y-1031930D01*
Y-1032770D01*
X57608Y-1033610D01*
X57295Y-1034345D01*
X56825Y-1034975D01*
X56277Y-1035395D01*
X55650Y-1035500D01*
G01X61950Y-1035710D02*
X61793Y-1035605D01*
Y-1035395D01*
X61950Y-1035290D01*
X62107Y-1035395D01*
Y-1035605D01*
X61950Y-1035710D01*
G01X66762Y-1030250D02*
X67232Y-1029620D01*
X67780Y-1029305D01*
X68407Y-1029200D01*
X69190Y-1029410D01*
X69738Y-1029935D01*
X69895Y-1030565D01*
X69817Y-1031195D01*
X69503Y-1031720D01*
X67937Y-1032770D01*
X67232Y-1033505D01*
X66762Y-1034555D01*
X66605Y-1035500D01*
X69895D01*
G01X74550D02*
Y-1029200D01*
X73610Y-1030460D01*
G01Y-1035500D02*
X75490D01*
G01X80850D02*
Y-1029200D01*
X79910Y-1030460D01*
G01Y-1035500D02*
X81790D01*
G01X86993Y-1036655D02*
X87307Y-1035290D01*
G01X91100Y-1029200D02*
X92197Y-1035500D01*
X93450Y-1029200D01*
X94703Y-1035500D01*
X95800Y-1029200D01*
G01X101317Y-1035500D02*
X98183D01*
Y-1029200D01*
X101317D01*
G01X100063Y-1032245D02*
X98183D01*
G01X104248Y-1035500D02*
Y-1029200D01*
X107852Y-1035500D01*
Y-1029200D01*
G01X110705Y-1035500D02*
Y-1029200D01*
G01X113995D02*
Y-1035500D01*
G01Y-1032350D02*
X110705D01*
G01X116927Y-1029200D02*
Y-1033715D01*
X117240Y-1034660D01*
X117867Y-1035290D01*
X118650Y-1035500D01*
X119433Y-1035290D01*
X120060Y-1034660D01*
X120373Y-1033715D01*
Y-1029200D01*
G01X122992Y-1035500D02*
X124950Y-1029200D01*
X126908Y-1035500D01*
G01X126203Y-1033295D02*
X123697D01*
G01X136062Y-1030250D02*
X136532Y-1029620D01*
X137080Y-1029305D01*
X137707Y-1029200D01*
X138490Y-1029410D01*
X139038Y-1029935D01*
X139195Y-1030565D01*
X139117Y-1031195D01*
X138803Y-1031720D01*
X137237Y-1032770D01*
X136532Y-1033505D01*
X136062Y-1034555D01*
X135905Y-1035500D01*
X139195D01*
G01X142048D02*
Y-1029200D01*
X145652Y-1035500D01*
Y-1029200D01*
G01X148427Y-1035500D02*
Y-1029200D01*
X149993D01*
X150620Y-1029515D01*
X151090Y-1029935D01*
X151482Y-1030565D01*
X151795Y-1031300D01*
X151873Y-1032350D01*
X151795Y-1033400D01*
X151482Y-1034135D01*
X151090Y-1034765D01*
X150620Y-1035185D01*
X149993Y-1035500D01*
X148427D01*
G01X161183D02*
Y-1029200D01*
X163142D01*
X163768Y-1029515D01*
X164160Y-1029935D01*
X164317Y-1030775D01*
X164160Y-1031615D01*
X163690Y-1032140D01*
X163142Y-1032455D01*
X161183D01*
G01X163142D02*
X164317Y-1035500D01*
G01X167327D02*
Y-1029200D01*
X168893D01*
X169520Y-1029515D01*
X169990Y-1029935D01*
X170382Y-1030565D01*
X170695Y-1031300D01*
X170773Y-1032350D01*
X170695Y-1033400D01*
X170382Y-1034135D01*
X169990Y-1034765D01*
X169520Y-1035185D01*
X168893Y-1035500D01*
X167327D01*
G01X175350Y-1035710D02*
X175193Y-1035605D01*
Y-1035395D01*
X175350Y-1035290D01*
X175507Y-1035395D01*
Y-1035605D01*
X175350Y-1035710D01*
G01X243000Y-1004500D02*
Y-1012500D01*
X247000D01*
G01X254800D02*
Y-1007167D01*
G01Y-1008100D02*
X254400Y-1007567D01*
X253800Y-1007300D01*
X253100Y-1007167D01*
X252400Y-1007433D01*
X251800Y-1007967D01*
X251400Y-1008767D01*
X251200Y-1009833D01*
X251400Y-1010900D01*
X251800Y-1011700D01*
X252400Y-1012233D01*
X253100Y-1012500D01*
X253800Y-1012367D01*
X254400Y-1011967D01*
X254800Y-1011434D01*
G01X258900Y-1014900D02*
X259500Y-1015167D01*
X260300Y-1014900D01*
X260800Y-1014367D01*
X261200Y-1013700D01*
X261800Y-1011567D01*
X263100Y-1007167D01*
G01X259900D02*
X261800Y-1011567D01*
G01X267500Y-1008900D02*
X270700D01*
X270400Y-1007967D01*
X269900Y-1007433D01*
X269200Y-1007167D01*
X268500Y-1007300D01*
X267900Y-1007700D01*
X267500Y-1008633D01*
X267300Y-1009434D01*
Y-1010233D01*
X267500Y-1011033D01*
X268000Y-1011833D01*
X268600Y-1012367D01*
X269300Y-1012500D01*
X270000Y-1012233D01*
X270700Y-1011434D01*
G01X275600Y-1012500D02*
Y-1007167D01*
G01Y-1008233D02*
X276100Y-1007700D01*
X276600Y-1007300D01*
X277300Y-1007167D01*
X277800Y-1007300D01*
X278400Y-1007700D01*
G01X262100Y-1054500D02*
X265900D01*
X262100Y-1062500D01*
X265900D01*
G01X272000Y-1057167D02*
Y-1062500D01*
G01Y-1055033D02*
X271800Y-1054900D01*
Y-1054633D01*
X272000Y-1054500D01*
X272200Y-1054633D01*
Y-1054900D01*
X272000Y-1055033D01*
G01X278700Y-1059833D02*
X281300D01*
G01X286200Y-1065167D02*
Y-1057167D01*
G01Y-1058367D02*
X286700Y-1057700D01*
X287200Y-1057300D01*
X288000Y-1057167D01*
X288700Y-1057300D01*
X289400Y-1057967D01*
X289700Y-1058900D01*
X289800Y-1059833D01*
X289700Y-1060767D01*
X289400Y-1061700D01*
X288800Y-1062233D01*
X288000Y-1062500D01*
X287300Y-1062367D01*
X286600Y-1061967D01*
X286200Y-1061434D01*
G01X296000Y-1057167D02*
Y-1062500D01*
G01Y-1055033D02*
X295800Y-1054900D01*
Y-1054633D01*
X296000Y-1054500D01*
X296200Y-1054633D01*
Y-1054900D01*
X296000Y-1055033D01*
G01X302300Y-1062500D02*
Y-1057167D01*
G01Y-1058500D02*
X302700Y-1057833D01*
X303300Y-1057300D01*
X304100Y-1057167D01*
X304800Y-1057300D01*
X305400Y-1057833D01*
X305700Y-1058767D01*
Y-1062500D01*
G01X310600Y-1064500D02*
X311300Y-1065033D01*
X312100Y-1065167D01*
X312800Y-1065033D01*
X313400Y-1064367D01*
X313800Y-1063433D01*
Y-1057167D01*
G01Y-1058233D02*
X313400Y-1057700D01*
X312800Y-1057300D01*
X312100Y-1057167D01*
X311300Y-1057433D01*
X310800Y-1057967D01*
X310400Y-1058900D01*
X310200Y-1059833D01*
X310300Y-1060633D01*
X310700Y-1061567D01*
X311300Y-1062233D01*
X312100Y-1062500D01*
X312700Y-1062367D01*
X313400Y-1061833D01*
X313800Y-1061300D01*
G01X275300Y-1029500D02*
X277700D01*
G01X276500D02*
Y-1037500D01*
G01X275300D02*
X277700D01*
G01X282200D02*
Y-1029500D01*
X286800Y-1037500D01*
Y-1029500D01*
G01X290600Y-1030833D02*
X291200Y-1030033D01*
X291900Y-1029633D01*
X292700Y-1029500D01*
X293700Y-1029767D01*
X294400Y-1030433D01*
X294600Y-1031233D01*
X294500Y-1032034D01*
X294100Y-1032700D01*
X292100Y-1034033D01*
X291200Y-1034967D01*
X290600Y-1036300D01*
X290400Y-1037500D01*
X294600D01*
G01X296500Y-1012500D02*
X297200Y-1012367D01*
X298000Y-1011967D01*
X298500Y-1011300D01*
X298700Y-1010367D01*
X298500Y-1009434D01*
X297900Y-1008633D01*
X297000Y-1008233D01*
X296000D01*
X295400Y-1007967D01*
X294900Y-1007300D01*
X294700Y-1006367D01*
X295000Y-1005433D01*
X295700Y-1004767D01*
X296500Y-1004500D01*
X297300Y-1004767D01*
X298000Y-1005433D01*
X298300Y-1006367D01*
X298100Y-1007300D01*
X297600Y-1007967D01*
X297000Y-1008233D01*
X296000D01*
X295100Y-1008633D01*
X294500Y-1009434D01*
X294300Y-1010367D01*
X294500Y-1011300D01*
X295000Y-1011967D01*
X295800Y-1012367D01*
X296500Y-1012500D01*
G01X369600Y-1055833D02*
X370200Y-1055033D01*
X370900Y-1054633D01*
X371700Y-1054500D01*
X372700Y-1054767D01*
X373400Y-1055433D01*
X373600Y-1056233D01*
X373500Y-1057034D01*
X373100Y-1057700D01*
X371100Y-1059033D01*
X370200Y-1059967D01*
X369600Y-1061300D01*
X369400Y-1062500D01*
X373600D01*
G01X379500Y-1054500D02*
X378700Y-1054767D01*
X378100Y-1055433D01*
X377700Y-1056233D01*
X377400Y-1057300D01*
X377300Y-1058500D01*
X377400Y-1059700D01*
X377700Y-1060767D01*
X378100Y-1061567D01*
X378700Y-1062233D01*
X379500Y-1062500D01*
X380300Y-1062233D01*
X380900Y-1061567D01*
X381300Y-1060767D01*
X381600Y-1059700D01*
X381700Y-1058500D01*
X381600Y-1057300D01*
X381300Y-1056233D01*
X380900Y-1055433D01*
X380300Y-1054767D01*
X379500Y-1054500D01*
G01X385600Y-1055833D02*
X386200Y-1055033D01*
X386900Y-1054633D01*
X387700Y-1054500D01*
X388700Y-1054767D01*
X389400Y-1055433D01*
X389600Y-1056233D01*
X389500Y-1057034D01*
X389100Y-1057700D01*
X387100Y-1059033D01*
X386200Y-1059967D01*
X385600Y-1061300D01*
X385400Y-1062500D01*
X389600D01*
G01X393600Y-1055833D02*
X394200Y-1055033D01*
X394900Y-1054633D01*
X395700Y-1054500D01*
X396700Y-1054767D01*
X397400Y-1055433D01*
X397600Y-1056233D01*
X397500Y-1057034D01*
X397100Y-1057700D01*
X395100Y-1059033D01*
X394200Y-1059967D01*
X393600Y-1061300D01*
X393400Y-1062500D01*
X397600D01*
G01X401700Y-1062767D02*
X405300Y-1054500D01*
G01X411500Y-1062500D02*
Y-1054500D01*
X410300Y-1056100D01*
G01Y-1062500D02*
X412700D01*
G01X417600Y-1055833D02*
X418200Y-1055033D01*
X418900Y-1054633D01*
X419700Y-1054500D01*
X420700Y-1054767D01*
X421400Y-1055433D01*
X421600Y-1056233D01*
X421500Y-1057034D01*
X421100Y-1057700D01*
X419100Y-1059033D01*
X418200Y-1059967D01*
X417600Y-1061300D01*
X417400Y-1062500D01*
X421600D01*
G01X425700Y-1062767D02*
X429300Y-1054500D01*
G01X435500Y-1062500D02*
Y-1054500D01*
X434300Y-1056100D01*
G01Y-1062500D02*
X436700D01*
G01X441300Y-1060900D02*
X441900Y-1061833D01*
X442700Y-1062367D01*
X443600Y-1062500D01*
X444400Y-1062367D01*
X445200Y-1061700D01*
X445700Y-1060900D01*
X445800Y-1060100D01*
X445600Y-1059167D01*
X444900Y-1058500D01*
X444200Y-1058233D01*
X443300D01*
G01X444200D02*
X444800Y-1057833D01*
X445300Y-1057167D01*
X445500Y-1056367D01*
X445300Y-1055567D01*
X444800Y-1054900D01*
X443900Y-1054500D01*
X443000Y-1054633D01*
X442100Y-1055167D01*
G01X369300Y-1040000D02*
Y-1032000D01*
X371300D01*
X372100Y-1032400D01*
X372700Y-1032933D01*
X373200Y-1033733D01*
X373600Y-1034667D01*
X373700Y-1036000D01*
X373600Y-1037333D01*
X373200Y-1038267D01*
X372700Y-1039067D01*
X372100Y-1039600D01*
X371300Y-1040000D01*
X369300D01*
G01X377000D02*
X379500Y-1032000D01*
X382000Y-1040000D01*
G01X381100Y-1037200D02*
X377900D01*
G01X385600Y-1040000D02*
Y-1032000D01*
X389400D01*
G01X388000Y-1035867D02*
X385600D01*
G01X395500Y-1032000D02*
X394700Y-1032267D01*
X394100Y-1032933D01*
X393700Y-1033733D01*
X393400Y-1034800D01*
X393300Y-1036000D01*
X393400Y-1037200D01*
X393700Y-1038267D01*
X394100Y-1039067D01*
X394700Y-1039733D01*
X395500Y-1040000D01*
X396300Y-1039733D01*
X396900Y-1039067D01*
X397300Y-1038267D01*
X397600Y-1037200D01*
X397700Y-1036000D01*
X397600Y-1034800D01*
X397300Y-1033733D01*
X396900Y-1032933D01*
X396300Y-1032267D01*
X395500Y-1032000D01*
G01X403500D02*
Y-1040000D01*
G01X401200Y-1032000D02*
X405800D01*
G01X409500Y-1040000D02*
Y-1032000D01*
X411900D01*
X412700Y-1032400D01*
X413300Y-1033333D01*
X413500Y-1034400D01*
X413300Y-1035467D01*
X412800Y-1036267D01*
X411900Y-1036667D01*
X409500D01*
G01X420300Y-1035733D02*
X420700Y-1035333D01*
X421000Y-1034667D01*
X421200Y-1033733D01*
X421000Y-1032933D01*
X420600Y-1032400D01*
X419900Y-1032000D01*
X417200D01*
Y-1040000D01*
X420500D01*
X421200Y-1039467D01*
X421600Y-1038667D01*
X421800Y-1037733D01*
X421600Y-1036800D01*
X421000Y-1036000D01*
X420300Y-1035733D01*
X417200D01*
G01X427500Y-1040000D02*
Y-1032000D01*
X426300Y-1033600D01*
G01Y-1040000D02*
X428700D01*
G01X433000D02*
X435500Y-1032000D01*
X438000Y-1040000D01*
G01X437100Y-1037200D02*
X433900D01*
G01X441600Y-1040000D02*
Y-1032000D01*
X445400D01*
G01X444000Y-1035867D02*
X441600D01*
G01X451500Y-1032000D02*
X450700Y-1032267D01*
X450100Y-1032933D01*
X449700Y-1033733D01*
X449400Y-1034800D01*
X449300Y-1036000D01*
X449400Y-1037200D01*
X449700Y-1038267D01*
X450100Y-1039067D01*
X450700Y-1039733D01*
X451500Y-1040000D01*
X452300Y-1039733D01*
X452900Y-1039067D01*
X453300Y-1038267D01*
X453600Y-1037200D01*
X453700Y-1036000D01*
X453600Y-1034800D01*
X453300Y-1033733D01*
X452900Y-1032933D01*
X452300Y-1032267D01*
X451500Y-1032000D01*
G01X389600Y-1012500D02*
Y-1004500D01*
X393400D01*
G01X392000Y-1008367D02*
X389600D01*
G01X399500Y-1004500D02*
X398700Y-1004767D01*
X398100Y-1005433D01*
X397700Y-1006233D01*
X397400Y-1007300D01*
X397300Y-1008500D01*
X397400Y-1009700D01*
X397700Y-1010767D01*
X398100Y-1011567D01*
X398700Y-1012233D01*
X399500Y-1012500D01*
X400300Y-1012233D01*
X400900Y-1011567D01*
X401300Y-1010767D01*
X401600Y-1009700D01*
X401700Y-1008500D01*
X401600Y-1007300D01*
X401300Y-1006233D01*
X400900Y-1005433D01*
X400300Y-1004767D01*
X399500Y-1004500D01*
G01X407500D02*
Y-1012500D01*
G01X405200Y-1004500D02*
X409800D01*
G01X412500Y-1015167D02*
X418500D01*
G01X421500Y-1012500D02*
Y-1004500D01*
X423900D01*
X424700Y-1004900D01*
X425300Y-1005833D01*
X425500Y-1006900D01*
X425300Y-1007967D01*
X424800Y-1008767D01*
X423900Y-1009167D01*
X421500D01*
G01X429300Y-1012500D02*
Y-1004500D01*
X431300D01*
X432100Y-1004900D01*
X432700Y-1005433D01*
X433200Y-1006233D01*
X433600Y-1007167D01*
X433700Y-1008500D01*
X433600Y-1009833D01*
X433200Y-1010767D01*
X432700Y-1011567D01*
X432100Y-1012100D01*
X431300Y-1012500D01*
X429300D01*
G01X440300Y-1008233D02*
X440700Y-1007833D01*
X441000Y-1007167D01*
X441200Y-1006233D01*
X441000Y-1005433D01*
X440600Y-1004900D01*
X439900Y-1004500D01*
X437200D01*
Y-1012500D01*
X440500D01*
X441200Y-1011967D01*
X441600Y-1011167D01*
X441800Y-1010233D01*
X441600Y-1009300D01*
X441000Y-1008500D01*
X440300Y-1008233D01*
X437200D01*
G01X444500Y-1015167D02*
X450500D01*
G01X456300Y-1008233D02*
X456700Y-1007833D01*
X457000Y-1007167D01*
X457200Y-1006233D01*
X457000Y-1005433D01*
X456600Y-1004900D01*
X455900Y-1004500D01*
X453200D01*
Y-1012500D01*
X456500D01*
X457200Y-1011967D01*
X457600Y-1011167D01*
X457800Y-1010233D01*
X457600Y-1009300D01*
X457000Y-1008500D01*
X456300Y-1008233D01*
X453200D01*
G01X461300Y-1012500D02*
Y-1004500D01*
X463300D01*
X464100Y-1004900D01*
X464700Y-1005433D01*
X465200Y-1006233D01*
X465600Y-1007167D01*
X465700Y-1008500D01*
X465600Y-1009833D01*
X465200Y-1010767D01*
X464700Y-1011567D01*
X464100Y-1012100D01*
X463300Y-1012500D01*
X461300D01*
G01X468500Y-1015167D02*
X474500D01*
G01X480100Y-1008500D02*
X482100D01*
Y-1010900D01*
X481500Y-1011700D01*
X480800Y-1012233D01*
X479800Y-1012500D01*
X478800Y-1012233D01*
X478100Y-1011700D01*
X477500Y-1010900D01*
X477100Y-1009967D01*
X476900Y-1008900D01*
Y-1007967D01*
X477100Y-1007167D01*
X477500Y-1006233D01*
X478100Y-1005433D01*
X478700Y-1004900D01*
X479500Y-1004500D01*
X480200D01*
X481000Y-1004767D01*
X481600Y-1005300D01*
G01X485500Y-1012500D02*
Y-1004500D01*
X487900D01*
X488700Y-1004900D01*
X489300Y-1005833D01*
X489500Y-1006900D01*
X489300Y-1007967D01*
X488800Y-1008767D01*
X487900Y-1009167D01*
X485500D01*
G01X493300Y-1004500D02*
Y-1010233D01*
X493700Y-1011434D01*
X494500Y-1012233D01*
X495500Y-1012500D01*
X496500Y-1012233D01*
X497300Y-1011434D01*
X497700Y-1010233D01*
Y-1004500D01*
G01X458000Y-1065500D02*
Y-1057500D01*
X456800Y-1059100D01*
G01Y-1065500D02*
X459200D01*
G01X464100Y-1062167D02*
X464800Y-1061233D01*
X465400Y-1060700D01*
X466200Y-1060433D01*
X466900Y-1060700D01*
X467400Y-1061233D01*
X467800Y-1062033D01*
X467900Y-1062967D01*
X467800Y-1063767D01*
X467400Y-1064567D01*
X466800Y-1065233D01*
X466100Y-1065500D01*
X465300Y-1065233D01*
X464600Y-1064434D01*
X464200Y-1063233D01*
X464100Y-1061900D01*
X464300Y-1060167D01*
X464600Y-1059233D01*
X465100Y-1058300D01*
X465800Y-1057633D01*
X466500Y-1057500D01*
X467200Y-1057767D01*
X467700Y-1058433D01*
G01X474000Y-1065767D02*
X473800Y-1065633D01*
Y-1065367D01*
X474000Y-1065233D01*
X474200Y-1065367D01*
Y-1065633D01*
X474000Y-1065767D01*
G01X480100Y-1062167D02*
X480800Y-1061233D01*
X481400Y-1060700D01*
X482200Y-1060433D01*
X482900Y-1060700D01*
X483400Y-1061233D01*
X483800Y-1062033D01*
X483900Y-1062967D01*
X483800Y-1063767D01*
X483400Y-1064567D01*
X482800Y-1065233D01*
X482100Y-1065500D01*
X481300Y-1065233D01*
X480600Y-1064434D01*
X480200Y-1063233D01*
X480100Y-1061900D01*
X480300Y-1060167D01*
X480600Y-1059233D01*
X481100Y-1058300D01*
X481800Y-1057633D01*
X482500Y-1057500D01*
X483200Y-1057767D01*
X483700Y-1058433D01*
G01X503000Y-1065500D02*
Y-1057500D01*
X501800Y-1059100D01*
G01Y-1065500D02*
X504200D01*
G01X510800D02*
X511000Y-1063767D01*
X511300Y-1062300D01*
X511700Y-1060967D01*
X512200Y-1059500D01*
X513000Y-1057500D01*
X509000D01*
G01X519000Y-1065767D02*
X518800Y-1065633D01*
Y-1065367D01*
X519000Y-1065233D01*
X519200Y-1065367D01*
Y-1065633D01*
X519000Y-1065767D01*
G01X525100Y-1058833D02*
X525700Y-1058033D01*
X526400Y-1057633D01*
X527200Y-1057500D01*
X528200Y-1057767D01*
X528900Y-1058433D01*
X529100Y-1059233D01*
X529000Y-1060034D01*
X528600Y-1060700D01*
X526600Y-1062033D01*
X525700Y-1062967D01*
X525100Y-1064300D01*
X524900Y-1065500D01*
X529100D01*
G01X523100Y-1040500D02*
Y-1032500D01*
X526900D01*
G01X525500Y-1036367D02*
X523100D01*
G54D14*
X137303Y601693D03*
Y609567D03*
Y617441D03*
Y625315D03*
Y633189D03*
Y641063D03*
Y648937D03*
Y656811D03*
Y664685D03*
X163878Y601693D03*
X156004D03*
X145177D03*
X163878Y609567D03*
Y617441D03*
Y625315D03*
Y633189D03*
X156004Y609567D03*
Y617441D03*
Y625315D03*
Y633189D03*
X145177Y609567D03*
Y617441D03*
Y625315D03*
Y633189D03*
X163878Y641063D03*
Y648937D03*
Y656811D03*
X156004Y641063D03*
Y648937D03*
Y656811D03*
X145177Y641063D03*
Y648937D03*
Y656811D03*
X163878Y664685D03*
X156004D03*
X145177D03*
X192126Y633189D03*
Y625315D03*
Y617441D03*
Y656811D03*
Y648937D03*
Y664685D03*
X200000Y633189D03*
Y625315D03*
Y617441D03*
X215748Y633189D03*
Y625315D03*
Y617441D03*
X223622Y633189D03*
Y625315D03*
Y617441D03*
X215748Y656811D03*
Y648937D03*
X223622Y656811D03*
Y648937D03*
X200000Y656811D03*
Y648937D03*
X215748Y664685D03*
X223622D03*
X200000D03*
X255906Y617441D03*
X248032D03*
X255906Y625315D03*
Y633189D03*
X248032D03*
Y625315D03*
X255906Y648937D03*
X248032D03*
X255906Y656811D03*
X248032D03*
X255906Y664685D03*
X248032D03*
X279528Y617441D03*
X271654D03*
X279528Y625315D03*
Y633189D03*
X271654D03*
Y625315D03*
X279528Y648937D03*
X271654D03*
X279528Y656811D03*
X271654D03*
X279528Y664685D03*
X271654D03*
X289646Y13012D03*
X295276Y617441D03*
Y625315D03*
Y633189D03*
X303150D03*
Y625315D03*
Y617441D03*
Y648937D03*
X295276D03*
X303150Y656811D03*
X295276D03*
X303150Y664685D03*
X295276D03*
X1437008Y617441D03*
X1429134D03*
X1437008Y625315D03*
Y633189D03*
X1429134D03*
Y625315D03*
X1437008Y648937D03*
X1429134D03*
X1437008Y656811D03*
X1429134D03*
X1437008Y664685D03*
X1429134D03*
X1460630Y617441D03*
X1452756D03*
X1460630Y625315D03*
Y633189D03*
X1452756D03*
Y625315D03*
X1460630Y648937D03*
X1452756D03*
X1460630Y656811D03*
X1452756D03*
X1460630Y664685D03*
X1452756D03*
X1480197Y13012D03*
X1476378Y617441D03*
Y625315D03*
Y633189D03*
X1484252D03*
Y625315D03*
Y617441D03*
Y648937D03*
X1476378D03*
X1484252Y656811D03*
X1476378D03*
X1484252Y664685D03*
X1476378D03*
X1508661Y633189D03*
Y625315D03*
Y617441D03*
X1516535Y633189D03*
Y625315D03*
Y617441D03*
X1508661Y656811D03*
Y648937D03*
X1516535Y656811D03*
Y648937D03*
X1508661Y664685D03*
X1516535D03*
X1532283Y633189D03*
Y625315D03*
Y617441D03*
X1540157Y633189D03*
Y625315D03*
Y617441D03*
X1532283Y656811D03*
Y648937D03*
X1540157Y656811D03*
Y648937D03*
X1532283Y664685D03*
X1540157D03*
X1587107Y601693D03*
X1576280D03*
X1568406D03*
X1587107Y609567D03*
Y617441D03*
Y625315D03*
Y633189D03*
X1576280Y609567D03*
Y617441D03*
Y625315D03*
Y633189D03*
X1568406Y609567D03*
Y617441D03*
Y625315D03*
Y633189D03*
X1587107Y641063D03*
Y648937D03*
Y656811D03*
X1576280Y641063D03*
Y648937D03*
Y656811D03*
X1568406Y641063D03*
Y648937D03*
Y656811D03*
X1587107Y664685D03*
X1576280D03*
X1568406D03*
X1594981Y601693D03*
Y609567D03*
Y617441D03*
Y625315D03*
Y633189D03*
Y641063D03*
Y648937D03*
Y656811D03*
Y664685D03*
G54D24*
G01X681604Y593187D02*
X976488D01*
X976998Y593697D01*
Y602677D01*
X976488Y603187D01*
X681604D01*
G01X1795600Y308000D02*
X1842744D01*
X1848957Y314213D01*
G54D15*
X166785Y230000D03*
Y310000D03*
Y390000D03*
Y470000D03*
Y550000D03*
X243785Y230000D03*
Y310000D03*
Y390000D03*
Y470000D03*
Y550000D03*
X1488500Y230000D03*
Y310000D03*
Y390000D03*
Y470000D03*
Y550000D03*
X1565500Y230000D03*
Y310000D03*
Y390000D03*
Y470000D03*
Y550000D03*
G54D16*
X681604Y593187D03*
Y603187D03*
G54D17*
X802087Y145984D03*
X792087D03*
X802087Y135984D03*
X792087D03*
X802087Y180984D03*
X792087D03*
X802087Y170984D03*
X792087D03*
X802087Y230984D03*
X792087D03*
X802087Y220984D03*
X792087D03*
X802087Y265984D03*
X792087D03*
X802087Y255984D03*
X792087D03*
X822087Y145984D03*
X812087D03*
X822087Y135984D03*
X812087D03*
X822087Y180984D03*
X812087D03*
X822087Y170984D03*
X812087D03*
X822087Y230984D03*
X812087D03*
X822087Y220984D03*
X812087D03*
X822087Y265984D03*
X812087D03*
X822087Y255984D03*
X812087D03*
X920197Y145984D03*
X910197D03*
X920197Y135984D03*
X910197D03*
X920197Y180984D03*
X910197D03*
X920197Y170984D03*
X910197D03*
X920197Y230984D03*
X910197D03*
X920197Y220984D03*
X910197D03*
X920197Y265984D03*
X910197D03*
X920197Y255984D03*
X910197D03*
X940197Y145984D03*
X930197D03*
X940197Y135984D03*
X930197D03*
X940197Y180984D03*
X930197D03*
X940197Y170984D03*
X930197D03*
X940197Y230984D03*
X930197D03*
X940197Y220984D03*
X930197D03*
X940197Y265984D03*
X930197D03*
X940197Y255984D03*
X930197D03*
G54D18*
G01X1144000Y372500D02*
X1148000Y368500D01*
X1161000D01*
X1167800Y361700D01*
Y355000D01*
X1642915Y111950D03*
X1639372Y114450D03*
X1646458Y111950D03*
X1642915Y114450D03*
X1639372Y111950D03*
X1646458Y114450D03*
X1650002Y111950D03*
Y114450D03*
G54D19*
X1848583Y99212D03*
X1848582Y481693D03*
M02*
